(kicad_sch
	(version 20250114)
	(generator "eeschema")
	(generator_version "9.0")
	(paper "A3")
	(title_block
		(title "COM Express 7 Baseboard")
		(date "2025-02-04")
		(rev "1.1.2")
		(company "Antmicro Ltd")
		(comment 1 "www.antmicro.com")
	)
	(bus_alias "UART"
		(members "RX" "TX")
	)
	(text "USB-C console"
		(exclude_from_sim no)
		(at 200.406 94.234 0)
		(effects
			(font
				(size 2 2)
				(thickness 0.4)
				(bold yes)
			)
			(justify left bottom)
		)
	)
	(text "RX"
		(exclude_from_sim no)
		(at 220.98 171.45 0)
		(effects
			(font
				(size 1.27 1.27)
			)
			(justify left bottom)
		)
	)
	(text "TX\n"
		(exclude_from_sim no)
		(at 231.14 171.45 0)
		(effects
			(font
				(size 1.27 1.27)
			)
			(justify left bottom)
		)
	)
	(text "TX/RX CROSS\n"
		(exclude_from_sim no)
		(at 234.95 127 0)
		(effects
			(font
				(size 1.27 1.27)
			)
			(justify left bottom)
		)
	)
	(junction
		(at 180.34 111.76)
		(diameter 0)
		(color 0 0 0 0)
	)
	(junction
		(at 124.46 205.74)
		(diameter 0)
		(color 0 0 0 0)
	)
	(junction
		(at 229.87 128.27)
		(diameter 0)
		(color 0 0 0 0)
	)
	(junction
		(at 161.29 139.7)
		(diameter 0)
		(color 0 0 0 0)
	)
	(junction
		(at 124.46 111.76)
		(diameter 0)
		(color 0 0 0 0)
	)
	(junction
		(at 124.46 191.77)
		(diameter 0)
		(color 0 0 0 0)
	)
	(junction
		(at 128.27 137.16)
		(diameter 0)
		(color 0 0 0 0)
	)
	(junction
		(at 224.79 161.29)
		(diameter 0)
		(color 0 0 0 0)
	)
	(junction
		(at 147.32 111.76)
		(diameter 0)
		(color 0 0 0 0)
	)
	(junction
		(at 189.23 130.81)
		(diameter 0)
		(color 0 0 0 0)
	)
	(junction
		(at 140.97 139.7)
		(diameter 0)
		(color 0 0 0 0)
	)
	(junction
		(at 151.13 137.16)
		(diameter 0)
		(color 0 0 0 0)
	)
	(junction
		(at 232.41 130.81)
		(diameter 0)
		(color 0 0 0 0)
	)
	(junction
		(at 175.26 123.19)
		(diameter 0)
		(color 0 0 0 0)
	)
	(junction
		(at 138.43 127)
		(diameter 0)
		(color 0 0 0 0)
	)
	(junction
		(at 125.73 139.7)
		(diameter 0)
		(color 0 0 0 0)
	)
	(junction
		(at 130.81 205.74)
		(diameter 0)
		(color 0 0 0 0)
	)
	(junction
		(at 293.37 111.76)
		(diameter 0)
		(color 0 0 0 0)
	)
	(junction
		(at 262.89 111.76)
		(diameter 0)
		(color 0 0 0 0)
	)
	(junction
		(at 143.51 137.16)
		(diameter 0)
		(color 0 0 0 0)
	)
	(junction
		(at 289.56 125.73)
		(diameter 0)
		(color 0 0 0 0)
	)
	(no_connect
		(at 123.19 170.18)
	)
	(no_connect
		(at 123.19 175.26)
	)
	(no_connect
		(at 123.19 147.32)
	)
	(no_connect
		(at 123.19 177.8)
	)
	(no_connect
		(at 123.19 152.4)
	)
	(no_connect
		(at 123.19 154.94)
	)
	(no_connect
		(at 123.19 167.64)
	)
	(no_connect
		(at 213.36 135.89)
	)
	(no_connect
		(at 123.19 162.56)
	)
	(no_connect
		(at 213.36 133.35)
	)
	(no_connect
		(at 123.19 144.78)
	)
	(no_connect
		(at 123.19 160.02)
	)
	(bus_entry
		(at 322.58 128.27)
		(size 1.27 -1.27)
		(stroke
			(width 0)
			(type default)
		)
	)
	(bus_entry
		(at 322.58 130.81)
		(size 1.27 -1.27)
		(stroke
			(width 0)
			(type default)
		)
	)
	(wire
		(pts
			(xy 138.43 142.24) (xy 133.35 142.24)
		)
		(stroke
			(width 0)
			(type default)
		)
	)
	(wire
		(pts
			(xy 189.23 130.81) (xy 190.5 130.81)
		)
		(stroke
			(width 0)
			(type default)
		)
	)
	(wire
		(pts
			(xy 210.82 161.29) (xy 224.79 161.29)
		)
		(stroke
			(width 0)
			(type default)
		)
	)
	(wire
		(pts
			(xy 213.36 143.51) (xy 232.41 143.51)
		)
		(stroke
			(width 0)
			(type default)
		)
	)
	(wire
		(pts
			(xy 143.51 137.16) (xy 143.51 143.51)
		)
		(stroke
			(width 0)
			(type default)
		)
	)
	(wire
		(pts
			(xy 266.7 111.76) (xy 266.7 125.73)
		)
		(stroke
			(width 0)
			(type default)
		)
	)
	(wire
		(pts
			(xy 130.81 205.74) (xy 130.81 207.01)
		)
		(stroke
			(width 0)
			(type default)
		)
	)
	(wire
		(pts
			(xy 128.27 137.16) (xy 143.51 137.16)
		)
		(stroke
			(width 0)
			(type default)
		)
	)
	(wire
		(pts
			(xy 189.23 148.59) (xy 189.23 151.13)
		)
		(stroke
			(width 0)
			(type default)
		)
	)
	(wire
		(pts
			(xy 267.97 133.35) (xy 266.7 133.35)
		)
		(stroke
			(width 0)
			(type default)
		)
	)
	(wire
		(pts
			(xy 210.82 181.61) (xy 229.87 181.61)
		)
		(stroke
			(width 0)
			(type default)
		)
	)
	(wire
		(pts
			(xy 187.96 143.51) (xy 190.5 143.51)
		)
		(stroke
			(width 0)
			(type default)
		)
	)
	(wire
		(pts
			(xy 227.33 123.19) (xy 229.87 123.19)
		)
		(stroke
			(width 0)
			(type default)
		)
	)
	(wire
		(pts
			(xy 266.7 125.73) (xy 267.97 125.73)
		)
		(stroke
			(width 0)
			(type default)
		)
	)
	(wire
		(pts
			(xy 125.73 134.62) (xy 125.73 139.7)
		)
		(stroke
			(width 0)
			(type default)
		)
	)
	(bus
		(pts
			(xy 323.85 125.73) (xy 323.85 127)
		)
		(stroke
			(width 0)
			(type default)
		)
	)
	(wire
		(pts
			(xy 138.43 143.51) (xy 138.43 142.24)
		)
		(stroke
			(width 0)
			(type default)
		)
	)
	(wire
		(pts
			(xy 189.23 130.81) (xy 182.88 130.81)
		)
		(stroke
			(width 0)
			(type default)
		)
	)
	(wire
		(pts
			(xy 229.87 181.61) (xy 229.87 176.53)
		)
		(stroke
			(width 0)
			(type default)
		)
	)
	(wire
		(pts
			(xy 128.27 132.08) (xy 128.27 137.16)
		)
		(stroke
			(width 0)
			(type default)
		)
	)
	(wire
		(pts
			(xy 213.36 148.59) (xy 233.68 148.59)
		)
		(stroke
			(width 0)
			(type default)
		)
	)
	(wire
		(pts
			(xy 227.33 120.65) (xy 232.41 120.65)
		)
		(stroke
			(width 0)
			(type default)
		)
	)
	(wire
		(pts
			(xy 262.89 118.11) (xy 262.89 119.38)
		)
		(stroke
			(width 0)
			(type default)
		)
	)
	(wire
		(pts
			(xy 250.19 130.81) (xy 247.65 128.27)
		)
		(stroke
			(width 0)
			(type default)
		)
	)
	(wire
		(pts
			(xy 140.97 139.7) (xy 140.97 143.51)
		)
		(stroke
			(width 0)
			(type default)
		)
	)
	(wire
		(pts
			(xy 147.32 120.65) (xy 147.32 118.11)
		)
		(stroke
			(width 0)
			(type default)
		)
	)
	(wire
		(pts
			(xy 171.45 137.16) (xy 190.5 137.16)
		)
		(stroke
			(width 0)
			(type default)
		)
	)
	(wire
		(pts
			(xy 130.81 182.88) (xy 123.19 182.88)
		)
		(stroke
			(width 0)
			(type default)
		)
	)
	(wire
		(pts
			(xy 213.36 128.27) (xy 229.87 128.27)
		)
		(stroke
			(width 0)
			(type default)
		)
	)
	(wire
		(pts
			(xy 130.81 182.88) (xy 130.81 205.74)
		)
		(stroke
			(width 0)
			(type default)
		)
	)
	(wire
		(pts
			(xy 300.99 128.27) (xy 322.58 128.27)
		)
		(stroke
			(width 0)
			(type default)
		)
	)
	(wire
		(pts
			(xy 123.19 127) (xy 128.27 127)
		)
		(stroke
			(width 0)
			(type default)
		)
	)
	(wire
		(pts
			(xy 124.46 111.76) (xy 124.46 119.38)
		)
		(stroke
			(width 0)
			(type default)
		)
	)
	(wire
		(pts
			(xy 189.23 128.27) (xy 190.5 128.27)
		)
		(stroke
			(width 0)
			(type default)
		)
	)
	(wire
		(pts
			(xy 180.34 111.76) (xy 180.34 113.03)
		)
		(stroke
			(width 0)
			(type default)
		)
	)
	(wire
		(pts
			(xy 133.35 127) (xy 138.43 127)
		)
		(stroke
			(width 0)
			(type default)
		)
	)
	(wire
		(pts
			(xy 124.46 205.74) (xy 124.46 201.93)
		)
		(stroke
			(width 0)
			(type default)
		)
	)
	(wire
		(pts
			(xy 262.89 111.76) (xy 266.7 111.76)
		)
		(stroke
			(width 0)
			(type default)
		)
	)
	(wire
		(pts
			(xy 232.41 130.81) (xy 247.65 130.81)
		)
		(stroke
			(width 0)
			(type default)
		)
	)
	(wire
		(pts
			(xy 262.89 111.76) (xy 262.89 113.03)
		)
		(stroke
			(width 0)
			(type default)
		)
	)
	(wire
		(pts
			(xy 120.65 205.74) (xy 120.65 201.93)
		)
		(stroke
			(width 0)
			(type default)
		)
	)
	(wire
		(pts
			(xy 133.35 124.46) (xy 138.43 124.46)
		)
		(stroke
			(width 0)
			(type default)
		)
	)
	(wire
		(pts
			(xy 224.79 161.29) (xy 229.87 161.29)
		)
		(stroke
			(width 0)
			(type default)
		)
	)
	(wire
		(pts
			(xy 229.87 123.19) (xy 229.87 128.27)
		)
		(stroke
			(width 0)
			(type default)
		)
	)
	(wire
		(pts
			(xy 124.46 111.76) (xy 147.32 111.76)
		)
		(stroke
			(width 0)
			(type default)
		)
	)
	(wire
		(pts
			(xy 180.34 111.76) (xy 189.23 111.76)
		)
		(stroke
			(width 0)
			(type default)
		)
	)
	(wire
		(pts
			(xy 124.46 205.74) (xy 120.65 205.74)
		)
		(stroke
			(width 0)
			(type default)
		)
	)
	(wire
		(pts
			(xy 224.79 161.29) (xy 224.79 162.56)
		)
		(stroke
			(width 0)
			(type default)
		)
	)
	(wire
		(pts
			(xy 293.37 111.76) (xy 293.37 113.03)
		)
		(stroke
			(width 0)
			(type default)
		)
	)
	(wire
		(pts
			(xy 190.5 133.35) (xy 189.23 133.35)
		)
		(stroke
			(width 0)
			(type default)
		)
	)
	(wire
		(pts
			(xy 229.87 161.29) (xy 229.87 162.56)
		)
		(stroke
			(width 0)
			(type default)
		)
	)
	(wire
		(pts
			(xy 123.19 111.76) (xy 124.46 111.76)
		)
		(stroke
			(width 0)
			(type default)
		)
	)
	(wire
		(pts
			(xy 266.7 133.35) (xy 266.7 134.62)
		)
		(stroke
			(width 0)
			(type default)
		)
	)
	(bus
		(pts
			(xy 325.12 124.46) (xy 326.39 124.46)
		)
		(stroke
			(width 0)
			(type default)
		)
	)
	(wire
		(pts
			(xy 224.79 179.07) (xy 224.79 176.53)
		)
		(stroke
			(width 0)
			(type default)
		)
	)
	(wire
		(pts
			(xy 123.19 185.42) (xy 124.46 185.42)
		)
		(stroke
			(width 0)
			(type default)
		)
	)
	(wire
		(pts
			(xy 124.46 196.85) (xy 124.46 191.77)
		)
		(stroke
			(width 0)
			(type default)
		)
	)
	(wire
		(pts
			(xy 170.18 143.51) (xy 182.88 143.51)
		)
		(stroke
			(width 0)
			(type default)
		)
	)
	(wire
		(pts
			(xy 147.32 111.76) (xy 180.34 111.76)
		)
		(stroke
			(width 0)
			(type default)
		)
	)
	(wire
		(pts
			(xy 161.29 142.24) (xy 161.29 139.7)
		)
		(stroke
			(width 0)
			(type default)
		)
	)
	(wire
		(pts
			(xy 289.56 133.35) (xy 288.29 133.35)
		)
		(stroke
			(width 0)
			(type default)
		)
	)
	(wire
		(pts
			(xy 123.19 124.46) (xy 128.27 124.46)
		)
		(stroke
			(width 0)
			(type default)
		)
	)
	(wire
		(pts
			(xy 293.37 110.49) (xy 293.37 111.76)
		)
		(stroke
			(width 0)
			(type default)
		)
	)
	(wire
		(pts
			(xy 124.46 119.38) (xy 123.19 119.38)
		)
		(stroke
			(width 0)
			(type default)
		)
	)
	(wire
		(pts
			(xy 288.29 125.73) (xy 289.56 125.73)
		)
		(stroke
			(width 0)
			(type default)
		)
	)
	(wire
		(pts
			(xy 133.35 142.24) (xy 133.35 143.51)
		)
		(stroke
			(width 0)
			(type default)
		)
	)
	(wire
		(pts
			(xy 295.91 130.81) (xy 288.29 130.81)
		)
		(stroke
			(width 0)
			(type default)
		)
	)
	(wire
		(pts
			(xy 289.56 111.76) (xy 289.56 125.73)
		)
		(stroke
			(width 0)
			(type default)
		)
	)
	(wire
		(pts
			(xy 171.45 139.7) (xy 190.5 139.7)
		)
		(stroke
			(width 0)
			(type default)
		)
	)
	(wire
		(pts
			(xy 175.26 123.19) (xy 175.26 124.46)
		)
		(stroke
			(width 0)
			(type default)
		)
	)
	(wire
		(pts
			(xy 247.65 130.81) (xy 250.19 128.27)
		)
		(stroke
			(width 0)
			(type default)
		)
	)
	(wire
		(pts
			(xy 289.56 125.73) (xy 289.56 133.35)
		)
		(stroke
			(width 0)
			(type default)
		)
	)
	(wire
		(pts
			(xy 295.91 128.27) (xy 288.29 128.27)
		)
		(stroke
			(width 0)
			(type default)
		)
	)
	(wire
		(pts
			(xy 182.88 130.81) (xy 182.88 123.19)
		)
		(stroke
			(width 0)
			(type default)
		)
	)
	(wire
		(pts
			(xy 300.99 130.81) (xy 322.58 130.81)
		)
		(stroke
			(width 0)
			(type default)
		)
	)
	(wire
		(pts
			(xy 293.37 118.11) (xy 293.37 119.38)
		)
		(stroke
			(width 0)
			(type default)
		)
	)
	(wire
		(pts
			(xy 229.87 167.64) (xy 229.87 171.45)
		)
		(stroke
			(width 0)
			(type default)
		)
	)
	(wire
		(pts
			(xy 151.13 137.16) (xy 166.37 137.16)
		)
		(stroke
			(width 0)
			(type default)
		)
	)
	(wire
		(pts
			(xy 130.81 205.74) (xy 124.46 205.74)
		)
		(stroke
			(width 0)
			(type default)
		)
	)
	(wire
		(pts
			(xy 120.65 196.85) (xy 120.65 191.77)
		)
		(stroke
			(width 0)
			(type default)
		)
	)
	(wire
		(pts
			(xy 189.23 133.35) (xy 189.23 130.81)
		)
		(stroke
			(width 0)
			(type default)
		)
	)
	(wire
		(pts
			(xy 140.97 139.7) (xy 161.29 139.7)
		)
		(stroke
			(width 0)
			(type default)
		)
	)
	(wire
		(pts
			(xy 123.19 134.62) (xy 125.73 134.62)
		)
		(stroke
			(width 0)
			(type default)
		)
	)
	(wire
		(pts
			(xy 165.1 123.19) (xy 175.26 123.19)
		)
		(stroke
			(width 0)
			(type default)
		)
	)
	(wire
		(pts
			(xy 123.19 137.16) (xy 128.27 137.16)
		)
		(stroke
			(width 0)
			(type default)
		)
	)
	(wire
		(pts
			(xy 151.13 137.16) (xy 151.13 142.24)
		)
		(stroke
			(width 0)
			(type default)
		)
	)
	(wire
		(pts
			(xy 250.19 128.27) (xy 267.97 128.27)
		)
		(stroke
			(width 0)
			(type default)
		)
	)
	(wire
		(pts
			(xy 120.65 191.77) (xy 124.46 191.77)
		)
		(stroke
			(width 0)
			(type default)
		)
	)
	(wire
		(pts
			(xy 293.37 111.76) (xy 289.56 111.76)
		)
		(stroke
			(width 0)
			(type default)
		)
	)
	(wire
		(pts
			(xy 213.36 130.81) (xy 232.41 130.81)
		)
		(stroke
			(width 0)
			(type default)
		)
	)
	(wire
		(pts
			(xy 210.82 179.07) (xy 224.79 179.07)
		)
		(stroke
			(width 0)
			(type default)
		)
	)
	(wire
		(pts
			(xy 175.26 123.19) (xy 182.88 123.19)
		)
		(stroke
			(width 0)
			(type default)
		)
	)
	(wire
		(pts
			(xy 125.73 139.7) (xy 140.97 139.7)
		)
		(stroke
			(width 0)
			(type default)
		)
	)
	(wire
		(pts
			(xy 189.23 111.76) (xy 189.23 128.27)
		)
		(stroke
			(width 0)
			(type default)
		)
	)
	(wire
		(pts
			(xy 138.43 127) (xy 138.43 128.27)
		)
		(stroke
			(width 0)
			(type default)
		)
	)
	(wire
		(pts
			(xy 161.29 139.7) (xy 166.37 139.7)
		)
		(stroke
			(width 0)
			(type default)
		)
	)
	(wire
		(pts
			(xy 138.43 124.46) (xy 138.43 127)
		)
		(stroke
			(width 0)
			(type default)
		)
	)
	(bus
		(pts
			(xy 323.85 127) (xy 323.85 129.54)
		)
		(stroke
			(width 0)
			(type default)
		)
	)
	(wire
		(pts
			(xy 213.36 146.05) (xy 232.41 146.05)
		)
		(stroke
			(width 0)
			(type default)
		)
	)
	(wire
		(pts
			(xy 224.79 167.64) (xy 224.79 171.45)
		)
		(stroke
			(width 0)
			(type default)
		)
	)
	(wire
		(pts
			(xy 143.51 137.16) (xy 151.13 137.16)
		)
		(stroke
			(width 0)
			(type default)
		)
	)
	(wire
		(pts
			(xy 250.19 130.81) (xy 267.97 130.81)
		)
		(stroke
			(width 0)
			(type default)
		)
	)
	(wire
		(pts
			(xy 123.19 139.7) (xy 125.73 139.7)
		)
		(stroke
			(width 0)
			(type default)
		)
	)
	(wire
		(pts
			(xy 147.32 111.76) (xy 147.32 113.03)
		)
		(stroke
			(width 0)
			(type default)
		)
	)
	(wire
		(pts
			(xy 190.5 148.59) (xy 189.23 148.59)
		)
		(stroke
			(width 0)
			(type default)
		)
	)
	(wire
		(pts
			(xy 232.41 120.65) (xy 232.41 130.81)
		)
		(stroke
			(width 0)
			(type default)
		)
	)
	(wire
		(pts
			(xy 123.19 132.08) (xy 128.27 132.08)
		)
		(stroke
			(width 0)
			(type default)
		)
	)
	(wire
		(pts
			(xy 124.46 185.42) (xy 124.46 191.77)
		)
		(stroke
			(width 0)
			(type default)
		)
	)
	(wire
		(pts
			(xy 213.36 140.97) (xy 233.68 140.97)
		)
		(stroke
			(width 0)
			(type default)
		)
	)
	(wire
		(pts
			(xy 229.87 128.27) (xy 247.65 128.27)
		)
		(stroke
			(width 0)
			(type default)
		)
	)
	(bus
		(pts
			(xy 323.85 125.73) (xy 325.12 124.46)
		)
		(stroke
			(width 0)
			(type default)
		)
	)
	(wire
		(pts
			(xy 251.46 111.76) (xy 262.89 111.76)
		)
		(stroke
			(width 0)
			(type default)
		)
	)
	(label "FTDI_CBUS0"
		(at 232.41 140.97 180)
		(effects
			(font
				(size 1.27 1.27)
			)
			(justify right bottom)
		)
	)
	(label "FTDI_LED_RX"
		(at 232.41 143.51 180)
		(effects
			(font
				(size 1.27 1.27)
			)
			(justify right bottom)
		)
	)
	(label "FTDI_D+"
		(at 176.53 137.16 0)
		(effects
			(font
				(size 1.27 1.27)
			)
			(justify left bottom)
		)
	)
	(label "FTDI_VCCIO"
		(at 210.82 161.29 0)
		(effects
			(font
				(size 1.27 1.27)
			)
			(justify left bottom)
		)
	)
	(label "UART_3V3.RX"
		(at 306.07 130.81 0)
		(effects
			(font
				(size 1.27 1.27)
			)
			(justify left bottom)
		)
	)
	(label "FTDI_LED_TX"
		(at 210.82 181.61 0)
		(effects
			(font
				(size 1.27 1.27)
			)
			(justify left bottom)
		)
	)
	(label "FTDI_D-"
		(at 176.53 139.7 0)
		(effects
			(font
				(size 1.27 1.27)
			)
			(justify left bottom)
		)
	)
	(label "FTDI_CBUS3"
		(at 232.41 148.59 180)
		(effects
			(font
				(size 1.27 1.27)
			)
			(justify right bottom)
		)
	)
	(label "FTDI_VCCIO"
		(at 165.1 123.19 0)
		(effects
			(font
				(size 1.27 1.27)
			)
			(justify left bottom)
		)
	)
	(label "FTDI_LED_RX"
		(at 210.82 179.07 0)
		(effects
			(font
				(size 1.27 1.27)
			)
			(justify left bottom)
		)
	)
	(label "SH"
		(at 124.46 191.77 180)
		(effects
			(font
				(size 1.27 1.27)
			)
			(justify right bottom)
		)
	)
	(label "UART_3V3.TX"
		(at 306.07 128.27 0)
		(effects
			(font
				(size 1.27 1.27)
			)
			(justify left bottom)
		)
	)
	(label "USB_D-"
		(at 130.81 139.7 0)
		(effects
			(font
				(size 1.27 1.27)
			)
			(justify left bottom)
		)
	)
	(label "FTDI_TX"
		(at 218.44 128.27 0)
		(effects
			(font
				(size 1.27 1.27)
			)
			(justify left bottom)
		)
	)
	(label "VBUS_FTDI"
		(at 251.46 111.76 0)
		(effects
			(font
				(size 1.27 1.27)
			)
			(justify left bottom)
		)
	)
	(label "USB_D+"
		(at 130.81 137.16 0)
		(effects
			(font
				(size 1.27 1.27)
			)
			(justify left bottom)
		)
	)
	(label "VBUS_FTDI"
		(at 152.4 111.76 0)
		(effects
			(font
				(size 1.27 1.27)
			)
			(justify left bottom)
		)
	)
	(label "FTDI_RX"
		(at 218.44 130.81 0)
		(effects
			(font
				(size 1.27 1.27)
			)
			(justify left bottom)
		)
	)
	(label "FTDI_VCCIO"
		(at 170.18 143.51 0)
		(effects
			(font
				(size 1.27 1.27)
			)
			(justify left bottom)
		)
	)
	(label "FTDI_LED_TX"
		(at 232.41 146.05 180)
		(effects
			(font
				(size 1.27 1.27)
			)
			(justify right bottom)
		)
	)
	(hierarchical_label "UART_3V3{UART}"
		(shape bidirectional)
		(at 326.39 124.46 0)
		(effects
			(font
				(size 1.27 1.27)
			)
			(justify left)
		)
	)
	(symbol
		(lib_id "antmicroTVSDiodes:TPD2E2U06_SC70")
		(at 143.51 143.51 270)
		(unit 1)
		(exclude_from_sim no)
		(in_bom yes)
		(on_board yes)
		(dnp no)
		(fields_autoplaced yes)
		(property "Reference" "D9"
			(at 140.97 153.67 90)
			(effects
				(font
					(size 1.27 1.27)
					(thickness 0.15)
				)
			)
		)
		(property "Value" "TPD2E2U06_SC70"
			(at 140.97 156.21 0)
			(effects
				(font
					(size 1.27 1.27)
					(thickness 0.15)
				)
				(justify left bottom)
				(hide yes)
			)
		)
		(property "Footprint" "antmicro-footprints:SC70-3"
			(at 138.43 156.21 0)
			(effects
				(font
					(size 1.27 1.27)
					(thickness 0.15)
				)
				(justify left bottom)
				(hide yes)
			)
		)
		(property "Datasheet" "https://www.ti.com/lit/ds/symlink/tpd2e2u06.pdf?ts=1706006131823&ref_url=https%253A%252F%252Fwww.ti.com%252Finterface%252Fdiodes%252Fesd-protection-diodes%252Fproducts.html"
			(at 135.89 156.21 0)
			(effects
				(font
					(size 1.27 1.27)
					(thickness 0.15)
				)
				(justify left bottom)
				(hide yes)
			)
		)
		(property "Description" ""
			(at 143.51 143.51 0)
			(effects
				(font
					(size 1.27 1.27)
				)
				(hide yes)
			)
		)
		(property "MPN" "TPD2E2U06DCKR"
			(at 140.97 156.21 90)
			(effects
				(font
					(size 1.27 1.27)
					(thickness 0.15)
				)
			)
		)
		(property "Manufacturer" "Texas Instruments"
			(at 133.35 156.21 0)
			(effects
				(font
					(size 1.27 1.27)
					(thickness 0.15)
				)
				(justify left bottom)
				(hide yes)
			)
		)
		(property "Author" "Antmicro"
			(at 130.81 156.21 0)
			(effects
				(font
					(size 1.27 1.27)
					(thickness 0.15)
				)
				(justify left bottom)
				(hide yes)
			)
		)
		(property "License" "Apache-2.0"
			(at 128.27 156.21 0)
			(effects
				(font
					(size 1.27 1.27)
					(thickness 0.15)
				)
				(justify left bottom)
				(hide yes)
			)
		)
		(pin "3"
		)
		(pin "1"
		)
		(pin "2"
		)
		(instances
			(project "com-express-7-baseboard"
				(path ""
					(reference "D9")
					(unit 1)
				)
			)
		)
	)
	(symbol
		(lib_id "antmicroUSBConnectors:USB-C_Kycon_KUSBX-SL2-CS1N24-B-TR")
		(at 123.19 119.38 0)
		(unit 1)
		(exclude_from_sim no)
		(in_bom yes)
		(on_board yes)
		(dnp no)
		(fields_autoplaced yes)
		(property "Reference" "J3"
			(at 99.06 151.13 0)
			(effects
				(font
					(size 1.27 1.27)
					(thickness 0.15)
				)
				(justify right)
			)
		)
		(property "Value" "USB-C_Kycon_KUSBX-SL2-CS1N24-B-TR"
			(at 99.06 153.67 0)
			(effects
				(font
					(size 1.27 1.27)
					(thickness 0.15)
				)
				(justify right)
			)
		)
		(property "Footprint" "antmicro-footprints:USB-C_Receptacle_Kycon_KUSBX-SL2-CS1N24-B-TR"
			(at 166.37 127 0)
			(effects
				(font
					(size 1.27 1.27)
					(thickness 0.15)
				)
				(justify left bottom)
				(hide yes)
			)
		)
		(property "Datasheet" "https://www.kycon.com/Pub_Eng_Draw/KUSBX-SL2-CS1N24-B-TR.pdf"
			(at 166.37 129.54 0)
			(effects
				(font
					(size 1.27 1.27)
					(thickness 0.15)
				)
				(justify left bottom)
				(hide yes)
			)
		)
		(property "Description" ""
			(at 123.19 119.38 0)
			(effects
				(font
					(size 1.27 1.27)
				)
				(hide yes)
			)
		)
		(property "MPN" "KUSBX-SL2-CS1N24-B-TR"
			(at 166.37 132.08 0)
			(effects
				(font
					(size 1.27 1.27)
					(thickness 0.15)
				)
				(justify left bottom)
				(hide yes)
			)
		)
		(property "Manufacturer" "Kycon"
			(at 166.37 134.62 0)
			(effects
				(font
					(size 1.27 1.27)
					(thickness 0.15)
				)
				(justify left bottom)
				(hide yes)
			)
		)
		(property "License" "Apache-2.0"
			(at 166.37 137.16 0)
			(effects
				(font
					(size 1.27 1.27)
					(thickness 0.15)
				)
				(justify left bottom)
				(hide yes)
			)
		)
		(property "Author" "Antmicro"
			(at 166.37 139.7 0)
			(effects
				(font
					(size 1.27 1.27)
					(thickness 0.15)
				)
				(justify left bottom)
				(hide yes)
			)
		)
		(pin "A1"
		)
		(pin "A10"
		)
		(pin "A11"
		)
		(pin "A12"
		)
		(pin "A2"
		)
		(pin "A3"
		)
		(pin "A4"
		)
		(pin "A5"
		)
		(pin "A6"
		)
		(pin "A7"
		)
		(pin "A8"
		)
		(pin "A9"
		)
		(pin "B1"
		)
		(pin "B10"
		)
		(pin "B11"
		)
		(pin "B12"
		)
		(pin "B2"
		)
		(pin "B3"
		)
		(pin "B4"
		)
		(pin "B5"
		)
		(pin "B6"
		)
		(pin "B7"
		)
		(pin "B8"
		)
		(pin "B9"
		)
		(pin "SH"
		)
		(instances
			(project "com-express-7-baseboard"
				(path ""
					(reference "J3")
					(unit 1)
				)
			)
		)
	)
	(symbol
		(lib_id "antmicropower:GND")
		(at 133.35 143.51 0)
		(unit 1)
		(exclude_from_sim no)
		(in_bom yes)
		(on_board yes)
		(dnp no)
		(property "Reference" "#PWR058"
			(at 142.24 146.05 0)
			(effects
				(font
					(size 1.27 1.27)
					(thickness 0.15)
				)
				(justify left bottom)
				(hide yes)
			)
		)
		(property "Value" "GND"
			(at 133.35 147.32 0)
			(effects
				(font
					(size 1.27 1.27)
					(thickness 0.15)
				)
			)
		)
		(property "Footprint" ""
			(at 142.24 151.13 0)
			(effects
				(font
					(size 1.27 1.27)
					(thickness 0.15)
				)
				(justify left bottom)
				(hide yes)
			)
		)
		(property "Datasheet" ""
			(at 142.24 156.21 0)
			(effects
				(font
					(size 1.27 1.27)
					(thickness 0.15)
				)
				(justify left bottom)
				(hide yes)
			)
		)
		(property "Description" ""
			(at 133.35 143.51 0)
			(effects
				(font
					(size 1.27 1.27)
				)
				(hide yes)
			)
		)
		(property "Author" "Antmicro"
			(at 142.24 151.13 0)
			(effects
				(font
					(size 1.27 1.27)
					(thickness 0.15)
				)
				(justify left bottom)
				(hide yes)
			)
		)
		(property "License" "Apache-2.0"
			(at 142.24 153.67 0)
			(effects
				(font
					(size 1.27 1.27)
					(thickness 0.15)
				)
				(justify left bottom)
				(hide yes)
			)
		)
		(pin "1"
		)
		(instances
			(project "com-express-7-baseboard"
				(path ""
					(reference "#PWR058")
					(unit 1)
				)
			)
		)
	)
	(symbol
		(lib_id "antmicropower:GND")
		(at 175.26 129.54 0)
		(mirror y)
		(unit 1)
		(exclude_from_sim no)
		(in_bom yes)
		(on_board yes)
		(dnp no)
		(property "Reference" "#PWR063"
			(at 166.37 132.08 0)
			(effects
				(font
					(size 1.27 1.27)
					(thickness 0.15)
				)
				(justify left bottom)
				(hide yes)
			)
		)
		(property "Value" "GND"
			(at 175.26 133.35 0)
			(effects
				(font
					(size 1.27 1.27)
					(thickness 0.15)
				)
			)
		)
		(property "Footprint" ""
			(at 166.37 137.16 0)
			(effects
				(font
					(size 1.27 1.27)
					(thickness 0.15)
				)
				(justify left bottom)
				(hide yes)
			)
		)
		(property "Datasheet" ""
			(at 166.37 142.24 0)
			(effects
				(font
					(size 1.27 1.27)
					(thickness 0.15)
				)
				(justify left bottom)
				(hide yes)
			)
		)
		(property "Description" ""
			(at 175.26 129.54 0)
			(effects
				(font
					(size 1.27 1.27)
				)
				(hide yes)
			)
		)
		(property "Author" "Antmicro"
			(at 166.37 137.16 0)
			(effects
				(font
					(size 1.27 1.27)
					(thickness 0.15)
				)
				(justify left bottom)
				(hide yes)
			)
		)
		(property "License" "Apache-2.0"
			(at 166.37 139.7 0)
			(effects
				(font
					(size 1.27 1.27)
					(thickness 0.15)
				)
				(justify left bottom)
				(hide yes)
			)
		)
		(pin "1"
		)
		(instances
			(project "com-express-7-baseboard"
				(path ""
					(reference "#PWR063")
					(unit 1)
				)
			)
		)
	)
	(symbol
		(lib_id "antmicroInterfaceControllers:FT230X_QFN")
		(at 190.5 128.27 0)
		(unit 1)
		(exclude_from_sim no)
		(in_bom yes)
		(on_board yes)
		(dnp no)
		(fields_autoplaced yes)
		(property "Reference" "U6"
			(at 201.93 120.65 0)
			(effects
				(font
					(size 1.27 1.27)
					(thickness 0.15)
				)
			)
		)
		(property "Value" "FT230X_QFN"
			(at 201.93 123.19 0)
			(effects
				(font
					(size 1.27 1.27)
					(thickness 0.15)
				)
				(hide yes)
			)
		)
		(property "Footprint" "antmicro-footprints:QFN-16-1EP_4x4mm_P0.65mm"
			(at 229.87 140.97 0)
			(effects
				(font
					(size 1.27 1.27)
					(thickness 0.15)
				)
				(justify left bottom)
				(hide yes)
			)
		)
		(property "Datasheet" "https://ftdichip.com/wp-content/uploads/2021/10/DS_FT230X.pdf"
			(at 229.87 143.51 0)
			(effects
				(font
					(size 1.27 1.27)
					(thickness 0.15)
				)
				(justify left bottom)
				(hide yes)
			)
		)
		(property "Description" ""
			(at 190.5 128.27 0)
			(effects
				(font
					(size 1.27 1.27)
				)
				(hide yes)
			)
		)
		(property "MPN" "FT230XQ-R"
			(at 201.93 123.19 0)
			(effects
				(font
					(size 1.27 1.27)
					(thickness 0.15)
				)
			)
		)
		(property "Manufacturer" "FTDI Chip"
			(at 229.87 146.05 0)
			(effects
				(font
					(size 1.27 1.27)
					(thickness 0.15)
				)
				(justify left bottom)
				(hide yes)
			)
		)
		(property "Author" "Antmicro"
			(at 229.87 151.13 0)
			(effects
				(font
					(size 1.27 1.27)
					(thickness 0.15)
				)
				(justify left bottom)
				(hide yes)
			)
		)
		(property "License" "Apache-2.0"
			(at 229.87 153.67 0)
			(effects
				(font
					(size 1.27 1.27)
					(thickness 0.15)
				)
				(justify left bottom)
				(hide yes)
			)
		)
		(pin "1"
		)
		(pin "10"
		)
		(pin "11"
		)
		(pin "12"
		)
		(pin "13"
		)
		(pin "14"
		)
		(pin "15"
		)
		(pin "16"
		)
		(pin "17"
		)
		(pin "2"
		)
		(pin "3"
		)
		(pin "4"
		)
		(pin "5"
		)
		(pin "6"
		)
		(pin "7"
		)
		(pin "8"
		)
		(pin "9"
		)
		(instances
			(project "com-express-7-baseboard"
				(path ""
					(reference "U6")
					(unit 1)
				)
			)
		)
	)
	(symbol
		(lib_id "antmicroResistors0402:R_0R_0402")
		(at 295.91 128.27 0)
		(unit 1)
		(exclude_from_sim no)
		(in_bom yes)
		(on_board yes)
		(dnp no)
		(property "Reference" "R74"
			(at 292.1 127 0)
			(effects
				(font
					(size 1.27 1.27)
					(thickness 0.15)
				)
			)
		)
		(property "Value" "R_0R_0402"
			(at 316.23 140.97 0)
			(effects
				(font
					(size 1.27 1.27)
					(thickness 0.15)
				)
				(justify left bottom)
				(hide yes)
			)
		)
		(property "Footprint" "antmicro-footprints:R_0402_1005Metric"
			(at 316.23 143.51 0)
			(effects
				(font
					(size 1.27 1.27)
					(thickness 0.15)
				)
				(justify left bottom)
				(hide yes)
			)
		)
		(property "Datasheet" "https://industrial.panasonic.com/cdbs/www-data/pdf/RDA0000/AOA0000C301.pdf"
			(at 316.23 146.05 0)
			(effects
				(font
					(size 1.27 1.27)
					(thickness 0.15)
				)
				(justify left bottom)
				(hide yes)
			)
		)
		(property "Description" ""
			(at 295.91 128.27 0)
			(effects
				(font
					(size 1.27 1.27)
				)
				(hide yes)
			)
		)
		(property "MPN" "ERJ2GE0R00X"
			(at 316.23 148.59 0)
			(effects
				(font
					(size 1.27 1.27)
					(thickness 0.15)
				)
				(justify left bottom)
				(hide yes)
			)
		)
		(property "Manufacturer" "Panasonic"
			(at 316.23 151.13 0)
			(effects
				(font
					(size 1.27 1.27)
					(thickness 0.15)
				)
				(justify left bottom)
				(hide yes)
			)
		)
		(property "License" "Apache-2.0"
			(at 316.23 153.67 0)
			(effects
				(font
					(size 1.27 1.27)
					(thickness 0.15)
				)
				(justify left bottom)
				(hide yes)
			)
		)
		(property "Author" "Antmicro"
			(at 316.23 156.21 0)
			(effects
				(font
					(size 1.27 1.27)
					(thickness 0.15)
				)
				(justify left bottom)
				(hide yes)
			)
		)
		(property "Val" "0R"
			(at 302.26 127 0)
			(effects
				(font
					(size 1.27 1.27)
					(thickness 0.15)
				)
			)
		)
		(property "Tolerance" "~"
			(at 316.23 138.43 0)
			(effects
				(font
					(size 1.27 1.27)
				)
				(justify left bottom)
				(hide yes)
			)
		)
		(property "Current" "1A"
			(at 316.23 158.75 0)
			(effects
				(font
					(size 1.27 1.27)
					(thickness 0.15)
				)
				(justify left bottom)
				(hide yes)
			)
		)
		(property "Public" "False"
			(at 316.23 158.75 0)
			(effects
				(font
					(size 1.27 1.27)
				)
				(justify left bottom)
				(hide yes)
			)
		)
		(pin "1"
		)
		(pin "2"
		)
		(instances
			(project "com-express-7-baseboard"
				(path ""
					(reference "R74")
					(unit 1)
				)
			)
		)
	)
	(symbol
		(lib_id "antmicropower:GND")
		(at 161.29 147.32 0)
		(mirror y)
		(unit 1)
		(exclude_from_sim no)
		(in_bom yes)
		(on_board yes)
		(dnp no)
		(property "Reference" "#PWR062"
			(at 152.4 149.86 0)
			(effects
				(font
					(size 1.27 1.27)
					(thickness 0.15)
				)
				(justify left bottom)
				(hide yes)
			)
		)
		(property "Value" "GND"
			(at 161.29 151.13 0)
			(effects
				(font
					(size 1.27 1.27)
					(thickness 0.15)
				)
			)
		)
		(property "Footprint" ""
			(at 152.4 154.94 0)
			(effects
				(font
					(size 1.27 1.27)
					(thickness 0.15)
				)
				(justify left bottom)
				(hide yes)
			)
		)
		(property "Datasheet" ""
			(at 152.4 160.02 0)
			(effects
				(font
					(size 1.27 1.27)
					(thickness 0.15)
				)
				(justify left bottom)
				(hide yes)
			)
		)
		(property "Description" ""
			(at 161.29 147.32 0)
			(effects
				(font
					(size 1.27 1.27)
				)
				(hide yes)
			)
		)
		(property "Author" "Antmicro"
			(at 152.4 154.94 0)
			(effects
				(font
					(size 1.27 1.27)
					(thickness 0.15)
				)
				(justify left bottom)
				(hide yes)
			)
		)
		(property "License" "Apache-2.0"
			(at 152.4 157.48 0)
			(effects
				(font
					(size 1.27 1.27)
					(thickness 0.15)
				)
				(justify left bottom)
				(hide yes)
			)
		)
		(pin "1"
		)
		(instances
			(project "com-express-7-baseboard"
				(path ""
					(reference "#PWR062")
					(unit 1)
				)
			)
		)
	)
	(symbol
		(lib_id "antmicroCapacitors0402:C_100n_0402")
		(at 124.46 196.85 90)
		(mirror x)
		(unit 1)
		(exclude_from_sim no)
		(in_bom yes)
		(on_board yes)
		(dnp no)
		(property "Reference" "C29"
			(at 130.81 198.12 90)
			(effects
				(font
					(size 1.27 1.27)
					(thickness 0.15)
				)
				(justify left)
			)
		)
		(property "Value" "C_100n_0402"
			(at 134.62 217.17 0)
			(effects
				(font
					(size 1.27 1.27)
					(thickness 0.15)
				)
				(justify left bottom)
				(hide yes)
			)
		)
		(property "Footprint" "antmicro-footprints:C_0402_1005Metric"
			(at 137.16 217.17 0)
			(effects
				(font
					(size 1.27 1.27)
					(thickness 0.15)
				)
				(justify left bottom)
				(hide yes)
			)
		)
		(property "Datasheet" "https://www.murata.com/products/productdetail?partno=GRM155R61H104KE14%23"
			(at 139.7 217.17 0)
			(effects
				(font
					(size 1.27 1.27)
					(thickness 0.15)
				)
				(justify left bottom)
				(hide yes)
			)
		)
		(property "Description" ""
			(at 124.46 196.85 0)
			(effects
				(font
					(size 1.27 1.27)
				)
				(hide yes)
			)
		)
		(property "MPN" "GRM155R61H104KE14D"
			(at 142.24 217.17 0)
			(effects
				(font
					(size 1.27 1.27)
					(thickness 0.15)
				)
				(justify left bottom)
				(hide yes)
			)
		)
		(property "Manufacturer" "Murata"
			(at 144.78 217.17 0)
			(effects
				(font
					(size 1.27 1.27)
					(thickness 0.15)
				)
				(justify left bottom)
				(hide yes)
			)
		)
		(property "License" "Apache-2.0"
			(at 147.32 217.17 0)
			(effects
				(font
					(size 1.27 1.27)
					(thickness 0.15)
				)
				(justify left bottom)
				(hide yes)
			)
		)
		(property "Author" "Antmicro"
			(at 149.86 217.17 0)
			(effects
				(font
					(size 1.27 1.27)
					(thickness 0.15)
				)
				(justify left bottom)
				(hide yes)
			)
		)
		(property "Val" "100n"
			(at 130.81 200.66 90)
			(effects
				(font
					(size 1.27 1.27)
					(thickness 0.15)
				)
				(justify left)
			)
		)
		(property "Voltage" "50V"
			(at 152.4 217.17 0)
			(effects
				(font
					(size 1.27 1.27)
				)
				(justify left bottom)
				(hide yes)
			)
		)
		(property "Dielectric" "X5R"
			(at 154.94 217.17 0)
			(effects
				(font
					(size 1.27 1.27)
				)
				(justify left bottom)
				(hide yes)
			)
		)
		(property "Public" "False"
			(at 157.48 217.17 0)
			(effects
				(font
					(size 1.27 1.27)
				)
				(justify left bottom)
				(hide yes)
			)
		)
		(pin "1"
		)
		(pin "2"
		)
		(instances
			(project "com-express-7-baseboard"
				(path ""
					(reference "C29")
					(unit 1)
				)
			)
		)
	)
	(symbol
		(lib_id "antmicroCapacitors0402:C_100n_0402")
		(at 175.26 129.54 90)
		(unit 1)
		(exclude_from_sim no)
		(in_bom yes)
		(on_board yes)
		(dnp no)
		(fields_autoplaced yes)
		(property "Reference" "C32"
			(at 177.8 125.7235 90)
			(effects
				(font
					(size 1.27 1.27)
					(thickness 0.15)
				)
				(justify right)
			)
		)
		(property "Value" "C_100n_0402"
			(at 185.42 109.22 0)
			(effects
				(font
					(size 1.27 1.27)
					(thickness 0.15)
				)
				(justify left bottom)
				(hide yes)
			)
		)
		(property "Footprint" "antmicro-footprints:C_0402_1005Metric"
			(at 187.96 109.22 0)
			(effects
				(font
					(size 1.27 1.27)
					(thickness 0.15)
				)
				(justify left bottom)
				(hide yes)
			)
		)
		(property "Datasheet" "https://www.murata.com/products/productdetail?partno=GRM155R61H104KE14%23"
			(at 190.5 109.22 0)
			(effects
				(font
					(size 1.27 1.27)
					(thickness 0.15)
				)
				(justify left bottom)
				(hide yes)
			)
		)
		(property "Description" ""
			(at 175.26 129.54 0)
			(effects
				(font
					(size 1.27 1.27)
				)
				(hide yes)
			)
		)
		(property "MPN" "GRM155R61H104KE14D"
			(at 193.04 109.22 0)
			(effects
				(font
					(size 1.27 1.27)
					(thickness 0.15)
				)
				(justify left bottom)
				(hide yes)
			)
		)
		(property "Manufacturer" "Murata"
			(at 195.58 109.22 0)
			(effects
				(font
					(size 1.27 1.27)
					(thickness 0.15)
				)
				(justify left bottom)
				(hide yes)
			)
		)
		(property "License" "Apache-2.0"
			(at 198.12 109.22 0)
			(effects
				(font
					(size 1.27 1.27)
					(thickness 0.15)
				)
				(justify left bottom)
				(hide yes)
			)
		)
		(property "Author" "Antmicro"
			(at 200.66 109.22 0)
			(effects
				(font
					(size 1.27 1.27)
					(thickness 0.15)
				)
				(justify left bottom)
				(hide yes)
			)
		)
		(property "Val" "100n"
			(at 177.8 128.2635 90)
			(effects
				(font
					(size 1.27 1.27)
					(thickness 0.15)
				)
				(justify right)
			)
		)
		(property "Voltage" "50V"
			(at 203.2 109.22 0)
			(effects
				(font
					(size 1.27 1.27)
				)
				(justify left bottom)
				(hide yes)
			)
		)
		(property "Dielectric" "X5R"
			(at 205.74 109.22 0)
			(effects
				(font
					(size 1.27 1.27)
				)
				(justify left bottom)
				(hide yes)
			)
		)
		(property "Public" "False"
			(at 208.28 109.22 0)
			(effects
				(font
					(size 1.27 1.27)
				)
				(justify left bottom)
				(hide yes)
			)
		)
		(pin "1"
		)
		(pin "2"
		)
		(instances
			(project "com-express-7-baseboard"
				(path ""
					(reference "C32")
					(unit 1)
				)
			)
		)
	)
	(symbol
		(lib_id "antmicroCapacitors0402:C_47p_0402")
		(at 151.13 147.32 90)
		(unit 1)
		(exclude_from_sim no)
		(in_bom yes)
		(on_board yes)
		(dnp no)
		(fields_autoplaced yes)
		(property "Reference" "C30"
			(at 153.67 143.5036 90)
			(effects
				(font
					(size 1.27 1.27)
					(thickness 0.15)
				)
				(justify right)
			)
		)
		(property "Value" "C_47p_0402"
			(at 161.29 127 0)
			(effects
				(font
					(size 1.27 1.27)
					(thickness 0.15)
				)
				(justify left bottom)
				(hide yes)
			)
		)
		(property "Footprint" "antmicro-footprints:C_0402_1005Metric"
			(at 163.83 127 0)
			(effects
				(font
					(size 1.27 1.27)
					(thickness 0.15)
				)
				(justify left bottom)
				(hide yes)
			)
		)
		(property "Datasheet" "https://www.kemet.com/en/us/capacitors/product/C0402C470J5GACTU.html"
			(at 166.37 127 0)
			(effects
				(font
					(size 1.27 1.27)
					(thickness 0.15)
				)
				(justify left bottom)
				(hide yes)
			)
		)
		(property "Description" ""
			(at 151.13 147.32 0)
			(effects
				(font
					(size 1.27 1.27)
				)
				(hide yes)
			)
		)
		(property "MPN" "C0402C470J5GACTU"
			(at 168.91 127 0)
			(effects
				(font
					(size 1.27 1.27)
					(thickness 0.15)
				)
				(justify left bottom)
				(hide yes)
			)
		)
		(property "Manufacturer" "KEMET"
			(at 171.45 127 0)
			(effects
				(font
					(size 1.27 1.27)
					(thickness 0.15)
				)
				(justify left bottom)
				(hide yes)
			)
		)
		(property "License" "Apache-2.0"
			(at 173.99 127 0)
			(effects
				(font
					(size 1.27 1.27)
					(thickness 0.15)
				)
				(justify left bottom)
				(hide yes)
			)
		)
		(property "Author" "Antmicro"
			(at 176.53 127 0)
			(effects
				(font
					(size 1.27 1.27)
					(thickness 0.15)
				)
				(justify left bottom)
				(hide yes)
			)
		)
		(property "Val" "47p"
			(at 153.67 146.0436 90)
			(effects
				(font
					(size 1.27 1.27)
					(thickness 0.15)
				)
				(justify right)
			)
		)
		(property "Voltage" ""
			(at 179.07 127 0)
			(effects
				(font
					(size 1.27 1.27)
				)
				(justify left bottom)
				(hide yes)
			)
		)
		(property "Dielectric" "C0G"
			(at 181.61 127 0)
			(effects
				(font
					(size 1.27 1.27)
				)
				(justify left bottom)
				(hide yes)
			)
		)
		(property "Public" "False"
			(at 184.15 127 0)
			(effects
				(font
					(size 1.27 1.27)
				)
				(justify left bottom)
				(hide yes)
			)
		)
		(pin "1"
		)
		(pin "2"
		)
		(instances
			(project "com-express-7-baseboard"
				(path ""
					(reference "C30")
					(unit 1)
				)
			)
		)
	)
	(symbol
		(lib_id "antmicropower:GND")
		(at 151.13 147.32 0)
		(mirror y)
		(unit 1)
		(exclude_from_sim no)
		(in_bom yes)
		(on_board yes)
		(dnp no)
		(property "Reference" "#PWR061"
			(at 142.24 149.86 0)
			(effects
				(font
					(size 1.27 1.27)
					(thickness 0.15)
				)
				(justify left bottom)
				(hide yes)
			)
		)
		(property "Value" "GND"
			(at 151.13 151.13 0)
			(effects
				(font
					(size 1.27 1.27)
					(thickness 0.15)
				)
			)
		)
		(property "Footprint" ""
			(at 142.24 154.94 0)
			(effects
				(font
					(size 1.27 1.27)
					(thickness 0.15)
				)
				(justify left bottom)
				(hide yes)
			)
		)
		(property "Datasheet" ""
			(at 142.24 160.02 0)
			(effects
				(font
					(size 1.27 1.27)
					(thickness 0.15)
				)
				(justify left bottom)
				(hide yes)
			)
		)
		(property "Description" ""
			(at 151.13 147.32 0)
			(effects
				(font
					(size 1.27 1.27)
				)
				(hide yes)
			)
		)
		(property "Author" "Antmicro"
			(at 142.24 154.94 0)
			(effects
				(font
					(size 1.27 1.27)
					(thickness 0.15)
				)
				(justify left bottom)
				(hide yes)
			)
		)
		(property "License" "Apache-2.0"
			(at 142.24 157.48 0)
			(effects
				(font
					(size 1.27 1.27)
					(thickness 0.15)
				)
				(justify left bottom)
				(hide yes)
			)
		)
		(pin "1"
		)
		(instances
			(project "com-express-7-baseboard"
				(path ""
					(reference "#PWR061")
					(unit 1)
				)
			)
		)
	)
	(symbol
		(lib_id "antmicroTestPoints:TP_0.75mm_SMD")
		(at 227.33 120.65 180)
		(unit 1)
		(exclude_from_sim no)
		(in_bom no)
		(on_board yes)
		(dnp no)
		(property "Reference" "TP7"
			(at 220.98 120.65 0)
			(effects
				(font
					(size 1.27 1.27)
					(thickness 0.15)
				)
			)
		)
		(property "Value" "TP_0.75mm_SMD"
			(at 216.535 116.84 0)
			(effects
				(font
					(size 1.27 1.27)
					(thickness 0.15)
				)
				(justify left bottom)
				(hide yes)
			)
		)
		(property "Footprint" "antmicro-footprints:TP_SMD_0.75mm"
			(at 216.535 114.3 0)
			(effects
				(font
					(size 1.27 1.27)
					(thickness 0.15)
				)
				(justify left bottom)
				(hide yes)
			)
		)
		(property "Datasheet" ""
			(at 209.55 107.95 0)
			(effects
				(font
					(size 1.27 1.27)
					(thickness 0.15)
				)
				(justify left bottom)
				(hide yes)
			)
		)
		(property "Description" ""
			(at 227.33 120.65 0)
			(effects
				(font
					(size 1.27 1.27)
				)
				(hide yes)
			)
		)
		(property "MPN" ""
			(at 216.535 109.22 0)
			(effects
				(font
					(size 1.27 1.27)
					(thickness 0.15)
				)
				(justify left bottom)
				(hide yes)
			)
		)
		(property "Manufacturer" ""
			(at 216.535 114.3 0)
			(effects
				(font
					(size 1.27 1.27)
					(thickness 0.15)
				)
				(justify left bottom)
				(hide yes)
			)
		)
		(property "Author" "Antmicro"
			(at 216.535 111.76 0)
			(effects
				(font
					(size 1.27 1.27)
					(thickness 0.15)
				)
				(justify left bottom)
				(hide yes)
			)
		)
		(property "License" "Apache-2.0"
			(at 216.535 109.22 0)
			(effects
				(font
					(size 1.27 1.27)
					(thickness 0.15)
				)
				(justify left bottom)
				(hide yes)
			)
		)
		(property "Public" "False"
			(at 217.17 106.68 0)
			(effects
				(font
					(size 1.27 1.27)
				)
				(justify left bottom)
				(hide yes)
			)
		)
		(pin "1"
		)
		(instances
			(project "com-express-7-baseboard"
				(path ""
					(reference "TP7")
					(unit 1)
				)
			)
		)
	)
	(symbol
		(lib_id "antmicroResistors0402:R_220R_0402")
		(at 224.79 167.64 90)
		(unit 1)
		(exclude_from_sim no)
		(in_bom yes)
		(on_board yes)
		(dnp no)
		(fields_autoplaced yes)
		(property "Reference" "R72"
			(at 222.25 163.8299 90)
			(effects
				(font
					(size 1.27 1.27)
					(thickness 0.15)
				)
				(justify left)
			)
		)
		(property "Value" "R_220R_0402"
			(at 237.49 147.32 0)
			(effects
				(font
					(size 1.27 1.27)
					(thickness 0.15)
				)
				(justify left bottom)
				(hide yes)
			)
		)
		(property "Footprint" "antmicro-footprints:R_0402_1005Metric"
			(at 240.03 147.32 0)
			(effects
				(font
					(size 1.27 1.27)
					(thickness 0.15)
				)
				(justify left bottom)
				(hide yes)
			)
		)
		(property "Datasheet" "https://www.bourns.com/docs/product-datasheets/cr.pdf"
			(at 242.57 147.32 0)
			(effects
				(font
					(size 1.27 1.27)
					(thickness 0.15)
				)
				(justify left bottom)
				(hide yes)
			)
		)
		(property "Description" ""
			(at 224.79 167.64 0)
			(effects
				(font
					(size 1.27 1.27)
				)
				(hide yes)
			)
		)
		(property "MPN" "CR0402-FX-2200GLF"
			(at 245.11 147.32 0)
			(effects
				(font
					(size 1.27 1.27)
					(thickness 0.15)
				)
				(justify left bottom)
				(hide yes)
			)
		)
		(property "Manufacturer" "Bourns"
			(at 247.65 147.32 0)
			(effects
				(font
					(size 1.27 1.27)
					(thickness 0.15)
				)
				(justify left bottom)
				(hide yes)
			)
		)
		(property "License" "Apache-2.0"
			(at 250.19 147.32 0)
			(effects
				(font
					(size 1.27 1.27)
					(thickness 0.15)
				)
				(justify left bottom)
				(hide yes)
			)
		)
		(property "Author" "Antmicro"
			(at 252.73 147.32 0)
			(effects
				(font
					(size 1.27 1.27)
					(thickness 0.15)
				)
				(justify left bottom)
				(hide yes)
			)
		)
		(property "Val" "220R"
			(at 222.25 166.3699 90)
			(effects
				(font
					(size 1.27 1.27)
					(thickness 0.15)
				)
				(justify left)
			)
		)
		(property "Tolerance" "1%"
			(at 234.95 147.32 0)
			(effects
				(font
					(size 1.27 1.27)
				)
				(justify left bottom)
				(hide yes)
			)
		)
		(property "Public" "False"
			(at 255.27 147.32 0)
			(effects
				(font
					(size 1.27 1.27)
				)
				(justify left bottom)
				(hide yes)
			)
		)
		(pin "1"
		)
		(pin "2"
		)
		(instances
			(project "com-express-7-baseboard"
				(path ""
					(reference "R72")
					(unit 1)
				)
			)
		)
	)
	(symbol
		(lib_id "antmicroResistors0402:R_5k1_0402")
		(at 128.27 124.46 0)
		(unit 1)
		(exclude_from_sim no)
		(in_bom yes)
		(on_board yes)
		(dnp no)
		(property "Reference" "R67"
			(at 125.73 123.19 0)
			(effects
				(font
					(size 1.27 1.27)
					(thickness 0.15)
				)
			)
		)
		(property "Value" "R_5k1_0402"
			(at 148.59 137.16 0)
			(effects
				(font
					(size 1.27 1.27)
					(thickness 0.15)
				)
				(justify left bottom)
				(hide yes)
			)
		)
		(property "Footprint" "antmicro-footprints:R_0402_1005Metric"
			(at 148.59 139.7 0)
			(effects
				(font
					(size 1.27 1.27)
					(thickness 0.15)
				)
				(justify left bottom)
				(hide yes)
			)
		)
		(property "Datasheet" "https://www.bourns.com/docs/product-datasheets/cr.pdf"
			(at 148.59 142.24 0)
			(effects
				(font
					(size 1.27 1.27)
					(thickness 0.15)
				)
				(justify left bottom)
				(hide yes)
			)
		)
		(property "Description" ""
			(at 128.27 124.46 0)
			(effects
				(font
					(size 1.27 1.27)
				)
				(hide yes)
			)
		)
		(property "MPN" "CR0402-FX-5101GLF"
			(at 148.59 144.78 0)
			(effects
				(font
					(size 1.27 1.27)
					(thickness 0.15)
				)
				(justify left bottom)
				(hide yes)
			)
		)
		(property "Manufacturer" "Bourns"
			(at 148.59 147.32 0)
			(effects
				(font
					(size 1.27 1.27)
					(thickness 0.15)
				)
				(justify left bottom)
				(hide yes)
			)
		)
		(property "License" "Apache-2.0"
			(at 148.59 149.86 0)
			(effects
				(font
					(size 1.27 1.27)
					(thickness 0.15)
				)
				(justify left bottom)
				(hide yes)
			)
		)
		(property "Author" "Antmicro"
			(at 148.59 152.4 0)
			(effects
				(font
					(size 1.27 1.27)
					(thickness 0.15)
				)
				(justify left bottom)
				(hide yes)
			)
		)
		(property "Val" "5k1"
			(at 134.62 123.19 0)
			(effects
				(font
					(size 1.27 1.27)
					(thickness 0.15)
				)
			)
		)
		(property "Tolerance" "1%"
			(at 148.59 134.62 0)
			(effects
				(font
					(size 1.27 1.27)
				)
				(justify left bottom)
				(hide yes)
			)
		)
		(property "Public" "False"
			(at 148.59 154.94 0)
			(effects
				(font
					(size 1.27 1.27)
				)
				(justify left bottom)
				(hide yes)
			)
		)
		(pin "1"
		)
		(pin "2"
		)
		(instances
			(project "com-express-7-baseboard"
				(path ""
					(reference "R67")
					(unit 1)
				)
			)
		)
	)
	(symbol
		(lib_id "antmicropower:GND")
		(at 262.89 119.38 0)
		(mirror y)
		(unit 1)
		(exclude_from_sim no)
		(in_bom yes)
		(on_board yes)
		(dnp no)
		(property "Reference" "#PWR066"
			(at 262.89 125.73 0)
			(effects
				(font
					(size 1.27 1.27)
				)
				(justify left bottom)
				(hide yes)
			)
		)
		(property "Value" "GND"
			(at 262.89 123.19 0)
			(effects
				(font
					(size 1.27 1.27)
				)
			)
		)
		(property "Footprint" ""
			(at 262.89 119.38 0)
			(effects
				(font
					(size 1.27 1.27)
				)
				(justify left bottom)
				(hide yes)
			)
		)
		(property "Datasheet" ""
			(at 262.89 119.38 0)
			(effects
				(font
					(size 1.27 1.27)
				)
				(justify left bottom)
				(hide yes)
			)
		)
		(property "Description" ""
			(at 262.89 119.38 0)
			(effects
				(font
					(size 1.27 1.27)
				)
				(hide yes)
			)
		)
		(property "Author" "Antmicro"
			(at 254 127 0)
			(effects
				(font
					(size 1.27 1.27)
					(thickness 0.15)
				)
				(justify left bottom)
				(hide yes)
			)
		)
		(property "License" "Apache-2.0"
			(at 254 129.54 0)
			(effects
				(font
					(size 1.27 1.27)
					(thickness 0.15)
				)
				(justify left bottom)
				(hide yes)
			)
		)
		(pin "1"
		)
		(instances
			(project "com-express-7-baseboard"
				(path ""
					(reference "#PWR066")
					(unit 1)
				)
			)
		)
	)
	(symbol
		(lib_id "antmicropower:PWR_FLAG")
		(at 123.19 111.76 90)
		(unit 1)
		(exclude_from_sim no)
		(in_bom yes)
		(on_board yes)
		(dnp no)
		(property "Reference" "#FLG01"
			(at 121.285 111.76 0)
			(effects
				(font
					(size 1.27 1.27)
				)
				(hide yes)
			)
		)
		(property "Value" "PWR_FLAG"
			(at 120.65 111.76 90)
			(effects
				(font
					(size 1.27 1.27)
				)
				(justify left)
			)
		)
		(property "Footprint" ""
			(at 123.19 111.76 0)
			(effects
				(font
					(size 1.27 1.27)
				)
				(hide yes)
			)
		)
		(property "Datasheet" ""
			(at 123.19 111.76 0)
			(effects
				(font
					(size 1.27 1.27)
				)
				(hide yes)
			)
		)
		(property "Description" ""
			(at 123.19 111.76 0)
			(effects
				(font
					(size 1.27 1.27)
				)
				(hide yes)
			)
		)
		(pin "1"
		)
		(instances
			(project "com-express-7-baseboard"
				(path ""
					(reference "#FLG01")
					(unit 1)
				)
			)
		)
	)
	(symbol
		(lib_id "antmicroResistors0402:R_220R_0402")
		(at 229.87 167.64 90)
		(unit 1)
		(exclude_from_sim no)
		(in_bom yes)
		(on_board yes)
		(dnp no)
		(fields_autoplaced yes)
		(property "Reference" "R73"
			(at 232.41 163.8299 90)
			(effects
				(font
					(size 1.27 1.27)
					(thickness 0.15)
				)
				(justify right)
			)
		)
		(property "Value" "R_220R_0402"
			(at 242.57 147.32 0)
			(effects
				(font
					(size 1.27 1.27)
					(thickness 0.15)
				)
				(justify left bottom)
				(hide yes)
			)
		)
		(property "Footprint" "antmicro-footprints:R_0402_1005Metric"
			(at 245.11 147.32 0)
			(effects
				(font
					(size 1.27 1.27)
					(thickness 0.15)
				)
				(justify left bottom)
				(hide yes)
			)
		)
		(property "Datasheet" "https://www.bourns.com/docs/product-datasheets/cr.pdf"
			(at 247.65 147.32 0)
			(effects
				(font
					(size 1.27 1.27)
					(thickness 0.15)
				)
				(justify left bottom)
				(hide yes)
			)
		)
		(property "Description" ""
			(at 229.87 167.64 0)
			(effects
				(font
					(size 1.27 1.27)
				)
				(hide yes)
			)
		)
		(property "MPN" "CR0402-FX-2200GLF"
			(at 250.19 147.32 0)
			(effects
				(font
					(size 1.27 1.27)
					(thickness 0.15)
				)
				(justify left bottom)
				(hide yes)
			)
		)
		(property "Manufacturer" "Bourns"
			(at 252.73 147.32 0)
			(effects
				(font
					(size 1.27 1.27)
					(thickness 0.15)
				)
				(justify left bottom)
				(hide yes)
			)
		)
		(property "License" "Apache-2.0"
			(at 255.27 147.32 0)
			(effects
				(font
					(size 1.27 1.27)
					(thickness 0.15)
				)
				(justify left bottom)
				(hide yes)
			)
		)
		(property "Author" "Antmicro"
			(at 257.81 147.32 0)
			(effects
				(font
					(size 1.27 1.27)
					(thickness 0.15)
				)
				(justify left bottom)
				(hide yes)
			)
		)
		(property "Val" "220R"
			(at 232.41 166.3699 90)
			(effects
				(font
					(size 1.27 1.27)
					(thickness 0.15)
				)
				(justify right)
			)
		)
		(property "Tolerance" "1%"
			(at 240.03 147.32 0)
			(effects
				(font
					(size 1.27 1.27)
				)
				(justify left bottom)
				(hide yes)
			)
		)
		(property "Public" "False"
			(at 260.35 147.32 0)
			(effects
				(font
					(size 1.27 1.27)
				)
				(justify left bottom)
				(hide yes)
			)
		)
		(pin "1"
		)
		(pin "2"
		)
		(instances
			(project "com-express-7-baseboard"
				(path ""
					(reference "R73")
					(unit 1)
				)
			)
		)
	)
	(symbol
		(lib_id "antmicroTestPoints:TP_0.75mm_SMD")
		(at 233.68 140.97 0)
		(unit 1)
		(exclude_from_sim no)
		(in_bom no)
		(on_board yes)
		(dnp no)
		(property "Reference" "TP9"
			(at 237.49 140.97 0)
			(effects
				(font
					(size 1.27 1.27)
				)
				(justify left)
			)
		)
		(property "Value" "TP_0.75mm_SMD"
			(at 248.92 148.59 0)
			(effects
				(font
					(size 1.27 1.27)
					(thickness 0.15)
				)
				(justify left bottom)
				(hide yes)
			)
		)
		(property "Footprint" "antmicro-footprints:TP_SMD_0.75mm"
			(at 248.92 151.13 0)
			(effects
				(font
					(size 1.27 1.27)
					(thickness 0.15)
				)
				(justify left bottom)
				(hide yes)
			)
		)
		(property "Datasheet" ""
			(at 248.92 153.67 0)
			(effects
				(font
					(size 1.27 1.27)
					(thickness 0.15)
				)
				(justify left bottom)
				(hide yes)
			)
		)
		(property "Description" ""
			(at 233.68 140.97 0)
			(effects
				(font
					(size 1.27 1.27)
				)
				(hide yes)
			)
		)
		(property "MPN" ""
			(at 233.68 140.97 0)
			(effects
				(font
					(size 1.27 1.27)
				)
				(justify left bottom)
				(hide yes)
			)
		)
		(property "Manufacturer" ""
			(at 233.68 140.97 0)
			(effects
				(font
					(size 1.27 1.27)
				)
				(justify left bottom)
				(hide yes)
			)
		)
		(property "Author" "Antmicro"
			(at 248.92 156.21 0)
			(effects
				(font
					(size 1.27 1.27)
					(thickness 0.15)
				)
				(justify left bottom)
				(hide yes)
			)
		)
		(property "License" "Apache-2.0"
			(at 248.92 158.75 0)
			(effects
				(font
					(size 1.27 1.27)
					(thickness 0.15)
				)
				(justify left bottom)
				(hide yes)
			)
		)
		(property "Public" "False"
			(at 243.84 154.94 0)
			(effects
				(font
					(size 1.27 1.27)
				)
				(justify left bottom)
				(hide yes)
			)
		)
		(pin "1"
		)
		(instances
			(project "com-express-7-baseboard"
				(path ""
					(reference "TP9")
					(unit 1)
				)
			)
		)
	)
	(symbol
		(lib_id "antmicroResistors0402:R_5k1_0402")
		(at 128.27 127 0)
		(unit 1)
		(exclude_from_sim no)
		(in_bom yes)
		(on_board yes)
		(dnp no)
		(property "Reference" "R68"
			(at 125.73 125.73 0)
			(effects
				(font
					(size 1.27 1.27)
					(thickness 0.15)
				)
			)
		)
		(property "Value" "R_5k1_0402"
			(at 148.59 139.7 0)
			(effects
				(font
					(size 1.27 1.27)
					(thickness 0.15)
				)
				(justify left bottom)
				(hide yes)
			)
		)
		(property "Footprint" "antmicro-footprints:R_0402_1005Metric"
			(at 148.59 142.24 0)
			(effects
				(font
					(size 1.27 1.27)
					(thickness 0.15)
				)
				(justify left bottom)
				(hide yes)
			)
		)
		(property "Datasheet" "https://www.bourns.com/docs/product-datasheets/cr.pdf"
			(at 148.59 144.78 0)
			(effects
				(font
					(size 1.27 1.27)
					(thickness 0.15)
				)
				(justify left bottom)
				(hide yes)
			)
		)
		(property "Description" ""
			(at 128.27 127 0)
			(effects
				(font
					(size 1.27 1.27)
				)
				(hide yes)
			)
		)
		(property "MPN" "CR0402-FX-5101GLF"
			(at 148.59 147.32 0)
			(effects
				(font
					(size 1.27 1.27)
					(thickness 0.15)
				)
				(justify left bottom)
				(hide yes)
			)
		)
		(property "Manufacturer" "Bourns"
			(at 148.59 149.86 0)
			(effects
				(font
					(size 1.27 1.27)
					(thickness 0.15)
				)
				(justify left bottom)
				(hide yes)
			)
		)
		(property "License" "Apache-2.0"
			(at 148.59 152.4 0)
			(effects
				(font
					(size 1.27 1.27)
					(thickness 0.15)
				)
				(justify left bottom)
				(hide yes)
			)
		)
		(property "Author" "Antmicro"
			(at 148.59 154.94 0)
			(effects
				(font
					(size 1.27 1.27)
					(thickness 0.15)
				)
				(justify left bottom)
				(hide yes)
			)
		)
		(property "Val" "5k1"
			(at 134.62 125.73 0)
			(effects
				(font
					(size 1.27 1.27)
					(thickness 0.15)
				)
			)
		)
		(property "Tolerance" "1%"
			(at 148.59 137.16 0)
			(effects
				(font
					(size 1.27 1.27)
				)
				(justify left bottom)
				(hide yes)
			)
		)
		(property "Public" "False"
			(at 148.59 157.48 0)
			(effects
				(font
					(size 1.27 1.27)
				)
				(justify left bottom)
				(hide yes)
			)
		)
		(pin "1"
		)
		(pin "2"
		)
		(instances
			(project "com-express-7-baseboard"
				(path ""
					(reference "R68")
					(unit 1)
				)
			)
		)
	)
	(symbol
		(lib_id "antmicropower:GND")
		(at 138.43 128.27 0)
		(mirror y)
		(unit 1)
		(exclude_from_sim no)
		(in_bom yes)
		(on_board yes)
		(dnp no)
		(property "Reference" "#PWR059"
			(at 129.54 130.81 0)
			(effects
				(font
					(size 1.27 1.27)
					(thickness 0.15)
				)
				(justify left bottom)
				(hide yes)
			)
		)
		(property "Value" "GND"
			(at 138.43 132.08 0)
			(effects
				(font
					(size 1.27 1.27)
					(thickness 0.15)
				)
			)
		)
		(property "Footprint" ""
			(at 129.54 135.89 0)
			(effects
				(font
					(size 1.27 1.27)
					(thickness 0.15)
				)
				(justify left bottom)
				(hide yes)
			)
		)
		(property "Datasheet" ""
			(at 129.54 140.97 0)
			(effects
				(font
					(size 1.27 1.27)
					(thickness 0.15)
				)
				(justify left bottom)
				(hide yes)
			)
		)
		(property "Description" ""
			(at 138.43 128.27 0)
			(effects
				(font
					(size 1.27 1.27)
				)
				(hide yes)
			)
		)
		(property "Author" "Antmicro"
			(at 129.54 135.89 0)
			(effects
				(font
					(size 1.27 1.27)
					(thickness 0.15)
				)
				(justify left bottom)
				(hide yes)
			)
		)
		(property "License" "Apache-2.0"
			(at 129.54 138.43 0)
			(effects
				(font
					(size 1.27 1.27)
					(thickness 0.15)
				)
				(justify left bottom)
				(hide yes)
			)
		)
		(pin "1"
		)
		(instances
			(project "com-express-7-baseboard"
				(path ""
					(reference "#PWR059")
					(unit 1)
				)
			)
		)
	)
	(symbol
		(lib_id "antmicroLEDIndicationDiscrete:LED_G_0603_LTST-C190GKT")
		(at 229.87 176.53 90)
		(unit 1)
		(exclude_from_sim no)
		(in_bom yes)
		(on_board yes)
		(dnp no)
		(property "Reference" "D12"
			(at 231.14 172.72 90)
			(effects
				(font
					(size 1.27 1.27)
				)
				(justify right)
			)
		)
		(property "Value" "LED_G_0603_LTST-C190GKT"
			(at 237.49 153.67 0)
			(effects
				(font
					(size 1.27 1.27)
					(thickness 0.15)
				)
				(justify left bottom)
				(hide yes)
			)
		)
		(property "Footprint" "antmicro-footprints:LED_0603_1608Metric_G"
			(at 240.03 153.67 0)
			(effects
				(font
					(size 1.27 1.27)
					(thickness 0.15)
				)
				(justify left bottom)
				(hide yes)
			)
		)
		(property "Datasheet" "https://media.digikey.com/pdf/Data%20Sheets/Lite-On%20PDFs/LTST-C190GKT.pdf"
			(at 242.57 153.67 0)
			(effects
				(font
					(size 1.27 1.27)
					(thickness 0.15)
				)
				(justify left bottom)
				(hide yes)
			)
		)
		(property "Description" ""
			(at 229.87 176.53 0)
			(effects
				(font
					(size 1.27 1.27)
				)
				(hide yes)
			)
		)
		(property "MPN" "LTST-C190GKT"
			(at 226.06 171.4501 90)
			(effects
				(font
					(size 1.27 1.27)
					(thickness 0.15)
				)
				(justify left)
				(hide yes)
			)
		)
		(property "Manufacturer" "Lite-On"
			(at 247.65 153.67 0)
			(effects
				(font
					(size 1.27 1.27)
					(thickness 0.15)
				)
				(justify left bottom)
				(hide yes)
			)
		)
		(property "Author" "Antmicro"
			(at 250.19 153.67 0)
			(effects
				(font
					(size 1.27 1.27)
					(thickness 0.15)
				)
				(justify left bottom)
				(hide yes)
			)
		)
		(property "License" "Apache-2.0"
			(at 252.73 153.67 0)
			(effects
				(font
					(size 1.27 1.27)
					(thickness 0.15)
				)
				(justify left bottom)
				(hide yes)
			)
		)
		(property "Public" "False"
			(at 247.65 156.21 0)
			(effects
				(font
					(size 1.27 1.27)
				)
				(justify left bottom)
				(hide yes)
			)
		)
		(property "Color" "Green"
			(at 231.14 175.26 90)
			(effects
				(font
					(size 1.27 1.27)
				)
				(justify right)
			)
		)
		(pin "1"
		)
		(pin "2"
		)
		(instances
			(project "com-express-7-baseboard"
				(path ""
					(reference "D12")
					(unit 1)
				)
			)
		)
	)
	(symbol
		(lib_id "antmicroResistors0402:R_0R_0402")
		(at 182.88 143.51 0)
		(unit 1)
		(exclude_from_sim no)
		(in_bom yes)
		(on_board yes)
		(dnp no)
		(property "Reference" "R71"
			(at 185.42 140.97 0)
			(effects
				(font
					(size 1.27 1.27)
					(thickness 0.15)
				)
			)
		)
		(property "Value" "R_0R_0402"
			(at 203.2 156.21 0)
			(effects
				(font
					(size 1.27 1.27)
					(thickness 0.15)
				)
				(justify left bottom)
				(hide yes)
			)
		)
		(property "Footprint" "antmicro-footprints:R_0402_1005Metric"
			(at 203.2 158.75 0)
			(effects
				(font
					(size 1.27 1.27)
					(thickness 0.15)
				)
				(justify left bottom)
				(hide yes)
			)
		)
		(property "Datasheet" "https://industrial.panasonic.com/cdbs/www-data/pdf/RDA0000/AOA0000C301.pdf"
			(at 203.2 161.29 0)
			(effects
				(font
					(size 1.27 1.27)
					(thickness 0.15)
				)
				(justify left bottom)
				(hide yes)
			)
		)
		(property "Description" ""
			(at 182.88 143.51 0)
			(effects
				(font
					(size 1.27 1.27)
				)
				(hide yes)
			)
		)
		(property "MPN" "ERJ2GE0R00X"
			(at 203.2 163.83 0)
			(effects
				(font
					(size 1.27 1.27)
					(thickness 0.15)
				)
				(justify left bottom)
				(hide yes)
			)
		)
		(property "Manufacturer" "Panasonic"
			(at 203.2 166.37 0)
			(effects
				(font
					(size 1.27 1.27)
					(thickness 0.15)
				)
				(justify left bottom)
				(hide yes)
			)
		)
		(property "License" "Apache-2.0"
			(at 203.2 168.91 0)
			(effects
				(font
					(size 1.27 1.27)
					(thickness 0.15)
				)
				(justify left bottom)
				(hide yes)
			)
		)
		(property "Author" "Antmicro"
			(at 203.2 171.45 0)
			(effects
				(font
					(size 1.27 1.27)
					(thickness 0.15)
				)
				(justify left bottom)
				(hide yes)
			)
		)
		(property "Val" "0R"
			(at 185.42 146.05 0)
			(effects
				(font
					(size 1.27 1.27)
					(thickness 0.15)
				)
			)
		)
		(property "Tolerance" "~"
			(at 203.2 153.67 0)
			(effects
				(font
					(size 1.27 1.27)
				)
				(justify left bottom)
				(hide yes)
			)
		)
		(property "Current" "1A"
			(at 203.2 173.99 0)
			(effects
				(font
					(size 1.27 1.27)
					(thickness 0.15)
				)
				(justify left bottom)
				(hide yes)
			)
		)
		(property "Public" "False"
			(at 203.2 173.99 0)
			(effects
				(font
					(size 1.27 1.27)
				)
				(justify left bottom)
				(hide yes)
			)
		)
		(pin "1"
		)
		(pin "2"
		)
		(instances
			(project "com-express-7-baseboard"
				(path ""
					(reference "R71")
					(unit 1)
				)
			)
		)
	)
	(symbol
		(lib_id "antmicroResistors0402:R_330R_0402")
		(at 120.65 196.85 90)
		(mirror x)
		(unit 1)
		(exclude_from_sim no)
		(in_bom yes)
		(on_board yes)
		(dnp no)
		(property "Reference" "R66"
			(at 119.38 198.12 90)
			(effects
				(font
					(size 1.27 1.27)
					(thickness 0.15)
				)
				(justify left)
			)
		)
		(property "Value" "R_330R_0402"
			(at 133.35 217.17 0)
			(effects
				(font
					(size 1.27 1.27)
					(thickness 0.15)
				)
				(justify left bottom)
				(hide yes)
			)
		)
		(property "Footprint" "antmicro-footprints:R_0402_1005Metric"
			(at 135.89 217.17 0)
			(effects
				(font
					(size 1.27 1.27)
					(thickness 0.15)
				)
				(justify left bottom)
				(hide yes)
			)
		)
		(property "Datasheet" "https://www.bourns.com/docs/product-datasheets/cr.pdf"
			(at 138.43 217.17 0)
			(effects
				(font
					(size 1.27 1.27)
					(thickness 0.15)
				)
				(justify left bottom)
				(hide yes)
			)
		)
		(property "Description" ""
			(at 120.65 196.85 0)
			(effects
				(font
					(size 1.27 1.27)
				)
				(hide yes)
			)
		)
		(property "MPN" "CR0402-FX-3300GLF"
			(at 140.97 217.17 0)
			(effects
				(font
					(size 1.27 1.27)
					(thickness 0.15)
				)
				(justify left bottom)
				(hide yes)
			)
		)
		(property "Manufacturer" "Bourns"
			(at 143.51 217.17 0)
			(effects
				(font
					(size 1.27 1.27)
					(thickness 0.15)
				)
				(justify left bottom)
				(hide yes)
			)
		)
		(property "License" "Apache-2.0"
			(at 146.05 217.17 0)
			(effects
				(font
					(size 1.27 1.27)
					(thickness 0.15)
				)
				(justify left bottom)
				(hide yes)
			)
		)
		(property "Author" "Antmicro"
			(at 148.59 217.17 0)
			(effects
				(font
					(size 1.27 1.27)
					(thickness 0.15)
				)
				(justify left bottom)
				(hide yes)
			)
		)
		(property "Val" "330R"
			(at 119.38 200.66 90)
			(effects
				(font
					(size 1.27 1.27)
					(thickness 0.15)
				)
				(justify left)
			)
		)
		(property "Tolerance" "1%"
			(at 130.81 217.17 0)
			(effects
				(font
					(size 1.27 1.27)
				)
				(justify left bottom)
				(hide yes)
			)
		)
		(property "Public" "False"
			(at 151.13 217.17 0)
			(effects
				(font
					(size 1.27 1.27)
				)
				(justify left bottom)
				(hide yes)
			)
		)
		(pin "1"
		)
		(pin "2"
		)
		(instances
			(project "com-express-7-baseboard"
				(path ""
					(reference "R66")
					(unit 1)
				)
			)
		)
	)
	(symbol
		(lib_id "antmicropower:+3V3")
		(at 293.37 110.49 0)
		(unit 1)
		(exclude_from_sim no)
		(in_bom yes)
		(on_board yes)
		(dnp no)
		(fields_autoplaced yes)
		(property "Reference" "#PWR068"
			(at 308.61 110.49 0)
			(effects
				(font
					(size 1.27 1.27)
					(thickness 0.15)
				)
				(justify left bottom)
				(hide yes)
			)
		)
		(property "Value" "+3V3"
			(at 293.37 105.41 0)
			(effects
				(font
					(size 1.27 1.27)
					(thickness 0.15)
				)
			)
		)
		(property "Footprint" ""
			(at 308.61 118.11 0)
			(effects
				(font
					(size 1.27 1.27)
					(thickness 0.15)
				)
				(justify left bottom)
				(hide yes)
			)
		)
		(property "Datasheet" ""
			(at 308.61 120.65 0)
			(effects
				(font
					(size 1.27 1.27)
					(thickness 0.15)
				)
				(justify left bottom)
				(hide yes)
			)
		)
		(property "Description" ""
			(at 293.37 110.49 0)
			(effects
				(font
					(size 1.27 1.27)
				)
				(hide yes)
			)
		)
		(property "Author" "Antmicro"
			(at 308.61 113.03 0)
			(effects
				(font
					(size 1.27 1.27)
					(thickness 0.15)
				)
				(justify left bottom)
				(hide yes)
			)
		)
		(property "License" "Apache-2.0"
			(at 308.61 115.57 0)
			(effects
				(font
					(size 1.27 1.27)
					(thickness 0.15)
				)
				(justify left bottom)
				(hide yes)
			)
		)
		(pin "1"
		)
		(instances
			(project "com-express-7-baseboard"
				(path ""
					(reference "#PWR068")
					(unit 1)
				)
			)
		)
	)
	(symbol
		(lib_id "antmicropower:PWR_FLAG")
		(at 165.1 123.19 90)
		(unit 1)
		(exclude_from_sim no)
		(in_bom yes)
		(on_board yes)
		(dnp no)
		(property "Reference" "#FLG02"
			(at 163.195 123.19 0)
			(effects
				(font
					(size 1.27 1.27)
				)
				(hide yes)
			)
		)
		(property "Value" "PWR_FLAG"
			(at 162.56 123.19 90)
			(effects
				(font
					(size 1.27 1.27)
				)
				(justify left)
			)
		)
		(property "Footprint" ""
			(at 165.1 123.19 0)
			(effects
				(font
					(size 1.27 1.27)
				)
				(hide yes)
			)
		)
		(property "Datasheet" ""
			(at 165.1 123.19 0)
			(effects
				(font
					(size 1.27 1.27)
				)
				(hide yes)
			)
		)
		(property "Description" ""
			(at 165.1 123.19 0)
			(effects
				(font
					(size 1.27 1.27)
				)
				(hide yes)
			)
		)
		(pin "1"
		)
		(instances
			(project "com-express-7-baseboard"
				(path ""
					(reference "#FLG02")
					(unit 1)
				)
			)
		)
	)
	(symbol
		(lib_id "antmicropower:GND")
		(at 266.7 134.62 0)
		(mirror y)
		(unit 1)
		(exclude_from_sim no)
		(in_bom yes)
		(on_board yes)
		(dnp no)
		(fields_autoplaced yes)
		(property "Reference" "#PWR067"
			(at 266.7 140.97 0)
			(effects
				(font
					(size 1.27 1.27)
				)
				(justify left bottom)
				(hide yes)
			)
		)
		(property "Value" "GND"
			(at 266.7 139.7 0)
			(effects
				(font
					(size 1.27 1.27)
				)
			)
		)
		(property "Footprint" ""
			(at 266.7 134.62 0)
			(effects
				(font
					(size 1.27 1.27)
				)
				(justify left bottom)
				(hide yes)
			)
		)
		(property "Datasheet" ""
			(at 266.7 134.62 0)
			(effects
				(font
					(size 1.27 1.27)
				)
				(justify left bottom)
				(hide yes)
			)
		)
		(property "Description" ""
			(at 266.7 134.62 0)
			(effects
				(font
					(size 1.27 1.27)
				)
				(hide yes)
			)
		)
		(property "Author" "Antmicro"
			(at 257.81 142.24 0)
			(effects
				(font
					(size 1.27 1.27)
					(thickness 0.15)
				)
				(justify left bottom)
				(hide yes)
			)
		)
		(property "License" "Apache-2.0"
			(at 257.81 144.78 0)
			(effects
				(font
					(size 1.27 1.27)
					(thickness 0.15)
				)
				(justify left bottom)
				(hide yes)
			)
		)
		(pin "1"
		)
		(instances
			(project "com-express-7-baseboard"
				(path ""
					(reference "#PWR067")
					(unit 1)
				)
			)
		)
	)
	(symbol
		(lib_id "antmicroResistors0402:R_27R_0402")
		(at 166.37 139.7 0)
		(unit 1)
		(exclude_from_sim no)
		(in_bom yes)
		(on_board yes)
		(dnp no)
		(property "Reference" "R70"
			(at 163.83 138.43 0)
			(effects
				(font
					(size 1.27 1.27)
					(thickness 0.15)
				)
			)
		)
		(property "Value" "R_27R_0402"
			(at 186.69 152.4 0)
			(effects
				(font
					(size 1.27 1.27)
					(thickness 0.15)
				)
				(justify left bottom)
				(hide yes)
			)
		)
		(property "Footprint" "antmicro-footprints:R_0402_1005Metric"
			(at 186.69 154.94 0)
			(effects
				(font
					(size 1.27 1.27)
					(thickness 0.15)
				)
				(justify left bottom)
				(hide yes)
			)
		)
		(property "Datasheet" "https://www.bourns.com/docs/product-datasheets/cr.pdf"
			(at 186.69 157.48 0)
			(effects
				(font
					(size 1.27 1.27)
					(thickness 0.15)
				)
				(justify left bottom)
				(hide yes)
			)
		)
		(property "Description" ""
			(at 166.37 139.7 0)
			(effects
				(font
					(size 1.27 1.27)
				)
				(hide yes)
			)
		)
		(property "MPN" "CR0402-FX-27R0GLF"
			(at 186.69 160.02 0)
			(effects
				(font
					(size 1.27 1.27)
					(thickness 0.15)
				)
				(justify left bottom)
				(hide yes)
			)
		)
		(property "Manufacturer" "Bourns"
			(at 186.69 162.56 0)
			(effects
				(font
					(size 1.27 1.27)
					(thickness 0.15)
				)
				(justify left bottom)
				(hide yes)
			)
		)
		(property "License" "Apache-2.0"
			(at 186.69 165.1 0)
			(effects
				(font
					(size 1.27 1.27)
					(thickness 0.15)
				)
				(justify left bottom)
				(hide yes)
			)
		)
		(property "Author" "Antmicro"
			(at 186.69 167.64 0)
			(effects
				(font
					(size 1.27 1.27)
					(thickness 0.15)
				)
				(justify left bottom)
				(hide yes)
			)
		)
		(property "Val" "27R"
			(at 172.72 138.43 0)
			(effects
				(font
					(size 1.27 1.27)
					(thickness 0.15)
				)
			)
		)
		(property "Tolerance" "1%"
			(at 186.69 149.86 0)
			(effects
				(font
					(size 1.27 1.27)
				)
				(justify left bottom)
				(hide yes)
			)
		)
		(property "Public" "False"
			(at 186.69 170.18 0)
			(effects
				(font
					(size 1.27 1.27)
				)
				(justify left bottom)
				(hide yes)
			)
		)
		(pin "1"
		)
		(pin "2"
		)
		(instances
			(project "com-express-7-baseboard"
				(path ""
					(reference "R70")
					(unit 1)
				)
			)
		)
	)
	(symbol
		(lib_id "antmicroResistors0402:R_27R_0402")
		(at 166.37 137.16 0)
		(unit 1)
		(exclude_from_sim no)
		(in_bom yes)
		(on_board yes)
		(dnp no)
		(property "Reference" "R69"
			(at 163.83 135.89 0)
			(effects
				(font
					(size 1.27 1.27)
					(thickness 0.15)
				)
			)
		)
		(property "Value" "R_27R_0402"
			(at 186.69 149.86 0)
			(effects
				(font
					(size 1.27 1.27)
					(thickness 0.15)
				)
				(justify left bottom)
				(hide yes)
			)
		)
		(property "Footprint" "antmicro-footprints:R_0402_1005Metric"
			(at 186.69 152.4 0)
			(effects
				(font
					(size 1.27 1.27)
					(thickness 0.15)
				)
				(justify left bottom)
				(hide yes)
			)
		)
		(property "Datasheet" "https://www.bourns.com/docs/product-datasheets/cr.pdf"
			(at 186.69 154.94 0)
			(effects
				(font
					(size 1.27 1.27)
					(thickness 0.15)
				)
				(justify left bottom)
				(hide yes)
			)
		)
		(property "Description" ""
			(at 166.37 137.16 0)
			(effects
				(font
					(size 1.27 1.27)
				)
				(hide yes)
			)
		)
		(property "MPN" "CR0402-FX-27R0GLF"
			(at 186.69 157.48 0)
			(effects
				(font
					(size 1.27 1.27)
					(thickness 0.15)
				)
				(justify left bottom)
				(hide yes)
			)
		)
		(property "Manufacturer" "Bourns"
			(at 186.69 160.02 0)
			(effects
				(font
					(size 1.27 1.27)
					(thickness 0.15)
				)
				(justify left bottom)
				(hide yes)
			)
		)
		(property "License" "Apache-2.0"
			(at 186.69 162.56 0)
			(effects
				(font
					(size 1.27 1.27)
					(thickness 0.15)
				)
				(justify left bottom)
				(hide yes)
			)
		)
		(property "Author" "Antmicro"
			(at 186.69 165.1 0)
			(effects
				(font
					(size 1.27 1.27)
					(thickness 0.15)
				)
				(justify left bottom)
				(hide yes)
			)
		)
		(property "Val" "27R"
			(at 172.72 135.89 0)
			(effects
				(font
					(size 1.27 1.27)
					(thickness 0.15)
				)
			)
		)
		(property "Tolerance" "1%"
			(at 186.69 147.32 0)
			(effects
				(font
					(size 1.27 1.27)
				)
				(justify left bottom)
				(hide yes)
			)
		)
		(property "Public" "False"
			(at 186.69 167.64 0)
			(effects
				(font
					(size 1.27 1.27)
				)
				(justify left bottom)
				(hide yes)
			)
		)
		(pin "1"
		)
		(pin "2"
		)
		(instances
			(project "com-express-7-baseboard"
				(path ""
					(reference "R69")
					(unit 1)
				)
			)
		)
	)
	(symbol
		(lib_id "antmicroCapacitors0402:C_47p_0402")
		(at 161.29 147.32 90)
		(unit 1)
		(exclude_from_sim no)
		(in_bom yes)
		(on_board yes)
		(dnp no)
		(fields_autoplaced yes)
		(property "Reference" "C31"
			(at 163.83 143.5036 90)
			(effects
				(font
					(size 1.27 1.27)
					(thickness 0.15)
				)
				(justify right)
			)
		)
		(property "Value" "C_47p_0402"
			(at 171.45 127 0)
			(effects
				(font
					(size 1.27 1.27)
					(thickness 0.15)
				)
				(justify left bottom)
				(hide yes)
			)
		)
		(property "Footprint" "antmicro-footprints:C_0402_1005Metric"
			(at 173.99 127 0)
			(effects
				(font
					(size 1.27 1.27)
					(thickness 0.15)
				)
				(justify left bottom)
				(hide yes)
			)
		)
		(property "Datasheet" "https://www.kemet.com/en/us/capacitors/product/C0402C470J5GACTU.html"
			(at 176.53 127 0)
			(effects
				(font
					(size 1.27 1.27)
					(thickness 0.15)
				)
				(justify left bottom)
				(hide yes)
			)
		)
		(property "Description" ""
			(at 161.29 147.32 0)
			(effects
				(font
					(size 1.27 1.27)
				)
				(hide yes)
			)
		)
		(property "MPN" "C0402C470J5GACTU"
			(at 179.07 127 0)
			(effects
				(font
					(size 1.27 1.27)
					(thickness 0.15)
				)
				(justify left bottom)
				(hide yes)
			)
		)
		(property "Manufacturer" "KEMET"
			(at 181.61 127 0)
			(effects
				(font
					(size 1.27 1.27)
					(thickness 0.15)
				)
				(justify left bottom)
				(hide yes)
			)
		)
		(property "License" "Apache-2.0"
			(at 184.15 127 0)
			(effects
				(font
					(size 1.27 1.27)
					(thickness 0.15)
				)
				(justify left bottom)
				(hide yes)
			)
		)
		(property "Author" "Antmicro"
			(at 186.69 127 0)
			(effects
				(font
					(size 1.27 1.27)
					(thickness 0.15)
				)
				(justify left bottom)
				(hide yes)
			)
		)
		(property "Val" "47p"
			(at 163.83 146.0436 90)
			(effects
				(font
					(size 1.27 1.27)
					(thickness 0.15)
				)
				(justify right)
			)
		)
		(property "Voltage" ""
			(at 189.23 127 0)
			(effects
				(font
					(size 1.27 1.27)
				)
				(justify left bottom)
				(hide yes)
			)
		)
		(property "Dielectric" "C0G"
			(at 191.77 127 0)
			(effects
				(font
					(size 1.27 1.27)
				)
				(justify left bottom)
				(hide yes)
			)
		)
		(property "Public" "False"
			(at 194.31 127 0)
			(effects
				(font
					(size 1.27 1.27)
				)
				(justify left bottom)
				(hide yes)
			)
		)
		(pin "1"
		)
		(pin "2"
		)
		(instances
			(project "com-express-7-baseboard"
				(path ""
					(reference "C31")
					(unit 1)
				)
			)
		)
	)
	(symbol
		(lib_id "antmicroCapacitors0402:C_100n_0402")
		(at 262.89 118.11 90)
		(unit 1)
		(exclude_from_sim no)
		(in_bom yes)
		(on_board yes)
		(dnp no)
		(fields_autoplaced yes)
		(property "Reference" "C34"
			(at 260.35 114.2935 90)
			(effects
				(font
					(size 1.27 1.27)
				)
				(justify left)
			)
		)
		(property "Value" "C_100n_0402"
			(at 266.7 118.11 0)
			(effects
				(font
					(size 1.27 1.27)
				)
				(justify left bottom)
				(hide yes)
			)
		)
		(property "Footprint" "antmicro-footprints:C_0402_1005Metric"
			(at 257.81 113.03 0)
			(effects
				(font
					(size 1.524 1.524)
				)
				(justify left bottom)
				(hide yes)
			)
		)
		(property "Datasheet" "https://www.murata.com/products/productdetail?partno=GRM155R61H104KE14%23"
			(at 262.89 118.11 0)
			(effects
				(font
					(size 1.27 1.27)
				)
				(justify left bottom)
				(hide yes)
			)
		)
		(property "Description" ""
			(at 262.89 118.11 0)
			(effects
				(font
					(size 1.27 1.27)
				)
				(hide yes)
			)
		)
		(property "Manufacturer" "Murata"
			(at 252.73 113.03 0)
			(effects
				(font
					(size 1.524 1.524)
				)
				(justify left bottom)
				(hide yes)
			)
		)
		(property "MPN" "GRM155R61H104KE14D"
			(at 255.27 113.03 0)
			(effects
				(font
					(size 1.524 1.524)
				)
				(justify left bottom)
				(hide yes)
			)
		)
		(property "Val" "100n"
			(at 260.35 116.8335 90)
			(effects
				(font
					(size 1.27 1.27)
				)
				(justify left)
			)
		)
		(property "License" "Apache-2.0"
			(at 285.75 97.79 0)
			(effects
				(font
					(size 1.27 1.27)
					(thickness 0.15)
				)
				(justify left bottom)
				(hide yes)
			)
		)
		(property "Author" "Antmicro"
			(at 288.29 97.79 0)
			(effects
				(font
					(size 1.27 1.27)
					(thickness 0.15)
				)
				(justify left bottom)
				(hide yes)
			)
		)
		(property "Voltage" "50V"
			(at 290.83 97.79 0)
			(effects
				(font
					(size 1.27 1.27)
				)
				(justify left bottom)
				(hide yes)
			)
		)
		(property "Dielectric" "X5R"
			(at 293.37 97.79 0)
			(effects
				(font
					(size 1.27 1.27)
				)
				(justify left bottom)
				(hide yes)
			)
		)
		(property "Public" "False"
			(at 295.91 97.79 0)
			(effects
				(font
					(size 1.27 1.27)
				)
				(justify left bottom)
				(hide yes)
			)
		)
		(pin "1"
		)
		(pin "2"
		)
		(instances
			(project "com-express-7-baseboard"
				(path ""
					(reference "C34")
					(unit 1)
				)
			)
		)
	)
	(symbol
		(lib_id "antmicroCapacitors0402:C_100n_0402")
		(at 293.37 118.11 90)
		(unit 1)
		(exclude_from_sim no)
		(in_bom yes)
		(on_board yes)
		(dnp no)
		(fields_autoplaced yes)
		(property "Reference" "C35"
			(at 295.91 114.2935 90)
			(effects
				(font
					(size 1.27 1.27)
				)
				(justify right)
			)
		)
		(property "Value" "C_100n_0402"
			(at 297.18 118.11 0)
			(effects
				(font
					(size 1.27 1.27)
				)
				(justify left bottom)
				(hide yes)
			)
		)
		(property "Footprint" "antmicro-footprints:C_0402_1005Metric"
			(at 288.29 113.03 0)
			(effects
				(font
					(size 1.524 1.524)
				)
				(justify left bottom)
				(hide yes)
			)
		)
		(property "Datasheet" "https://www.murata.com/products/productdetail?partno=GRM155R61H104KE14%23"
			(at 293.37 118.11 0)
			(effects
				(font
					(size 1.27 1.27)
				)
				(justify left bottom)
				(hide yes)
			)
		)
		(property "Description" ""
			(at 293.37 118.11 0)
			(effects
				(font
					(size 1.27 1.27)
				)
				(hide yes)
			)
		)
		(property "Manufacturer" "Murata"
			(at 283.21 113.03 0)
			(effects
				(font
					(size 1.524 1.524)
				)
				(justify left bottom)
				(hide yes)
			)
		)
		(property "MPN" "GRM155R61H104KE14D"
			(at 285.75 113.03 0)
			(effects
				(font
					(size 1.524 1.524)
				)
				(justify left bottom)
				(hide yes)
			)
		)
		(property "Val" "100n"
			(at 295.91 116.8335 90)
			(effects
				(font
					(size 1.27 1.27)
				)
				(justify right)
			)
		)
		(property "License" "Apache-2.0"
			(at 316.23 97.79 0)
			(effects
				(font
					(size 1.27 1.27)
					(thickness 0.15)
				)
				(justify left bottom)
				(hide yes)
			)
		)
		(property "Author" "Antmicro"
			(at 318.77 97.79 0)
			(effects
				(font
					(size 1.27 1.27)
					(thickness 0.15)
				)
				(justify left bottom)
				(hide yes)
			)
		)
		(property "Voltage" "50V"
			(at 321.31 97.79 0)
			(effects
				(font
					(size 1.27 1.27)
				)
				(justify left bottom)
				(hide yes)
			)
		)
		(property "Dielectric" "X5R"
			(at 323.85 97.79 0)
			(effects
				(font
					(size 1.27 1.27)
				)
				(justify left bottom)
				(hide yes)
			)
		)
		(property "Public" "False"
			(at 326.39 97.79 0)
			(effects
				(font
					(size 1.27 1.27)
				)
				(justify left bottom)
				(hide yes)
			)
		)
		(pin "1"
		)
		(pin "2"
		)
		(instances
			(project "com-express-7-baseboard"
				(path ""
					(reference "C35")
					(unit 1)
				)
			)
		)
	)
	(symbol
		(lib_id "antmicroTestPoints:TP_0.75mm_SMD")
		(at 227.33 123.19 180)
		(unit 1)
		(exclude_from_sim no)
		(in_bom no)
		(on_board yes)
		(dnp no)
		(property "Reference" "TP8"
			(at 220.98 123.19 0)
			(effects
				(font
					(size 1.27 1.27)
					(thickness 0.15)
				)
			)
		)
		(property "Value" "TP_0.75mm_SMD"
			(at 216.535 119.38 0)
			(effects
				(font
					(size 1.27 1.27)
					(thickness 0.15)
				)
				(justify left bottom)
				(hide yes)
			)
		)
		(property "Footprint" "antmicro-footprints:TP_SMD_0.75mm"
			(at 216.535 116.84 0)
			(effects
				(font
					(size 1.27 1.27)
					(thickness 0.15)
				)
				(justify left bottom)
				(hide yes)
			)
		)
		(property "Datasheet" ""
			(at 209.55 110.49 0)
			(effects
				(font
					(size 1.27 1.27)
					(thickness 0.15)
				)
				(justify left bottom)
				(hide yes)
			)
		)
		(property "Description" ""
			(at 227.33 123.19 0)
			(effects
				(font
					(size 1.27 1.27)
				)
				(hide yes)
			)
		)
		(property "MPN" ""
			(at 216.535 111.76 0)
			(effects
				(font
					(size 1.27 1.27)
					(thickness 0.15)
				)
				(justify left bottom)
				(hide yes)
			)
		)
		(property "Manufacturer" ""
			(at 216.535 116.84 0)
			(effects
				(font
					(size 1.27 1.27)
					(thickness 0.15)
				)
				(justify left bottom)
				(hide yes)
			)
		)
		(property "Author" "Antmicro"
			(at 216.535 114.3 0)
			(effects
				(font
					(size 1.27 1.27)
					(thickness 0.15)
				)
				(justify left bottom)
				(hide yes)
			)
		)
		(property "License" "Apache-2.0"
			(at 216.535 111.76 0)
			(effects
				(font
					(size 1.27 1.27)
					(thickness 0.15)
				)
				(justify left bottom)
				(hide yes)
			)
		)
		(property "Public" "False"
			(at 217.17 109.22 0)
			(effects
				(font
					(size 1.27 1.27)
				)
				(justify left bottom)
				(hide yes)
			)
		)
		(pin "1"
		)
		(instances
			(project "com-express-7-baseboard"
				(path ""
					(reference "TP8")
					(unit 1)
				)
			)
		)
	)
	(symbol
		(lib_id "antmicropower:GND")
		(at 180.34 118.11 0)
		(unit 1)
		(exclude_from_sim no)
		(in_bom yes)
		(on_board yes)
		(dnp no)
		(property "Reference" "#PWR064"
			(at 180.34 124.46 0)
			(effects
				(font
					(size 1.27 1.27)
				)
				(justify left bottom)
				(hide yes)
			)
		)
		(property "Value" "GND"
			(at 178.435 122.555 0)
			(effects
				(font
					(size 1.27 1.27)
				)
				(justify left bottom)
			)
		)
		(property "Footprint" ""
			(at 180.34 118.11 0)
			(effects
				(font
					(size 1.27 1.27)
				)
				(justify left bottom)
				(hide yes)
			)
		)
		(property "Datasheet" ""
			(at 180.34 118.11 0)
			(effects
				(font
					(size 1.27 1.27)
				)
				(justify left bottom)
				(hide yes)
			)
		)
		(property "Description" ""
			(at 180.34 118.11 0)
			(effects
				(font
					(size 1.27 1.27)
				)
				(hide yes)
			)
		)
		(property "Author" "Antmicro"
			(at 189.23 125.73 0)
			(effects
				(font
					(size 1.27 1.27)
					(thickness 0.15)
				)
				(justify left bottom)
				(hide yes)
			)
		)
		(property "License" "Apache-2.0"
			(at 189.23 128.27 0)
			(effects
				(font
					(size 1.27 1.27)
					(thickness 0.15)
				)
				(justify left bottom)
				(hide yes)
			)
		)
		(pin "1"
		)
		(instances
			(project "com-express-7-baseboard"
				(path ""
					(reference "#PWR064")
					(unit 1)
				)
			)
		)
	)
	(symbol
		(lib_id "antmicroTVSDiodes:PESD5Z5_0F")
		(at 147.32 113.03 270)
		(unit 1)
		(exclude_from_sim no)
		(in_bom yes)
		(on_board yes)
		(dnp no)
		(fields_autoplaced yes)
		(property "Reference" "D10"
			(at 149.86 114.3 90)
			(effects
				(font
					(size 1.27 1.27)
					(thickness 0.15)
				)
				(justify left)
			)
		)
		(property "Value" "PESD5Z5_0F"
			(at 144.78 115.8876 90)
			(effects
				(font
					(size 1.27 1.27)
					(thickness 0.15)
				)
				(justify right)
				(hide yes)
			)
		)
		(property "Footprint" "antmicro-footprints:SOD-523"
			(at 142.24 128.27 0)
			(effects
				(font
					(size 1.27 1.27)
					(thickness 0.15)
				)
				(justify left bottom)
				(hide yes)
			)
		)
		(property "Datasheet" "https://assets.nexperia.com/documents/data-sheet/PESD5Z5_0.pdf"
			(at 139.7 128.27 0)
			(effects
				(font
					(size 1.27 1.27)
					(thickness 0.15)
				)
				(justify left bottom)
				(hide yes)
			)
		)
		(property "Description" ""
			(at 147.32 113.03 0)
			(effects
				(font
					(size 1.27 1.27)
				)
				(hide yes)
			)
		)
		(property "Manufacturer" "Nexperia"
			(at 137.16 128.27 0)
			(effects
				(font
					(size 1.27 1.27)
					(thickness 0.15)
				)
				(justify left bottom)
				(hide yes)
			)
		)
		(property "MPN" "PESD5Z5.0F"
			(at 149.86 116.84 90)
			(effects
				(font
					(size 1.27 1.27)
					(thickness 0.15)
				)
				(justify left)
			)
		)
		(property "Author" "Antmicro"
			(at 132.08 128.27 0)
			(effects
				(font
					(size 1.27 1.27)
					(thickness 0.15)
				)
				(justify left bottom)
				(hide yes)
			)
		)
		(property "License" "Apache-2.0"
			(at 129.54 128.27 0)
			(effects
				(font
					(size 1.27 1.27)
					(thickness 0.15)
				)
				(justify left bottom)
				(hide yes)
			)
		)
		(property "Public" "False"
			(at 129.54 133.35 0)
			(effects
				(font
					(size 1.27 1.27)
				)
				(justify left bottom)
				(hide yes)
			)
		)
		(pin "1"
		)
		(pin "2"
		)
		(instances
			(project "com-express-7-baseboard"
				(path ""
					(reference "D10")
					(unit 1)
				)
			)
		)
	)
	(symbol
		(lib_id "antmicroCapacitors0402:C_1u_0402")
		(at 180.34 118.11 90)
		(unit 1)
		(exclude_from_sim no)
		(in_bom yes)
		(on_board yes)
		(dnp no)
		(fields_autoplaced yes)
		(property "Reference" "C33"
			(at 182.88 114.2935 90)
			(effects
				(font
					(size 1.27 1.27)
					(thickness 0.15)
				)
				(justify right)
			)
		)
		(property "Value" "C_1u_0402"
			(at 190.5 97.79 0)
			(effects
				(font
					(size 1.27 1.27)
					(thickness 0.15)
				)
				(justify left bottom)
				(hide yes)
			)
		)
		(property "Footprint" "antmicro-footprints:C_0402_1005Metric"
			(at 193.04 97.79 0)
			(effects
				(font
					(size 1.27 1.27)
					(thickness 0.15)
				)
				(justify left bottom)
				(hide yes)
			)
		)
		(property "Datasheet" "https://product.tdk.com/en/search/capacitor/ceramic/mlcc/info?part_no=C1005X6S1A105K050BC"
			(at 195.58 97.79 0)
			(effects
				(font
					(size 1.27 1.27)
					(thickness 0.15)
				)
				(justify left bottom)
				(hide yes)
			)
		)
		(property "Description" ""
			(at 180.34 118.11 0)
			(effects
				(font
					(size 1.27 1.27)
				)
				(hide yes)
			)
		)
		(property "MPN" "C1005X6S1A105K050BC"
			(at 198.12 97.79 0)
			(effects
				(font
					(size 1.27 1.27)
					(thickness 0.15)
				)
				(justify left bottom)
				(hide yes)
			)
		)
		(property "Manufacturer" "TDK"
			(at 200.66 97.79 0)
			(effects
				(font
					(size 1.27 1.27)
					(thickness 0.15)
				)
				(justify left bottom)
				(hide yes)
			)
		)
		(property "License" "Apache-2.0"
			(at 203.2 97.79 0)
			(effects
				(font
					(size 1.27 1.27)
					(thickness 0.15)
				)
				(justify left bottom)
				(hide yes)
			)
		)
		(property "Author" "Antmicro"
			(at 205.74 97.79 0)
			(effects
				(font
					(size 1.27 1.27)
					(thickness 0.15)
				)
				(justify left bottom)
				(hide yes)
			)
		)
		(property "Val" "1u"
			(at 182.88 116.8335 90)
			(effects
				(font
					(size 1.27 1.27)
					(thickness 0.15)
				)
				(justify right)
			)
		)
		(property "Voltage" ""
			(at 208.28 97.79 0)
			(effects
				(font
					(size 1.27 1.27)
				)
				(justify left bottom)
				(hide yes)
			)
		)
		(property "Dielectric" ""
			(at 210.82 97.79 0)
			(effects
				(font
					(size 1.27 1.27)
				)
				(justify left bottom)
				(hide yes)
			)
		)
		(property "Public" "False"
			(at 213.36 97.79 0)
			(effects
				(font
					(size 1.27 1.27)
				)
				(justify left bottom)
				(hide yes)
			)
		)
		(pin "1"
		)
		(pin "2"
		)
		(instances
			(project "com-express-7-baseboard"
				(path ""
					(reference "C33")
					(unit 1)
				)
			)
		)
	)
	(symbol
		(lib_id "antmicroTestPoints:TP_0.75mm_SMD")
		(at 233.68 148.59 0)
		(unit 1)
		(exclude_from_sim no)
		(in_bom no)
		(on_board yes)
		(dnp no)
		(property "Reference" "TP10"
			(at 237.49 148.59 0)
			(effects
				(font
					(size 1.27 1.27)
				)
				(justify left)
			)
		)
		(property "Value" "TP_0.75mm_SMD"
			(at 248.92 156.21 0)
			(effects
				(font
					(size 1.27 1.27)
					(thickness 0.15)
				)
				(justify left bottom)
				(hide yes)
			)
		)
		(property "Footprint" "antmicro-footprints:TP_SMD_0.75mm"
			(at 248.92 158.75 0)
			(effects
				(font
					(size 1.27 1.27)
					(thickness 0.15)
				)
				(justify left bottom)
				(hide yes)
			)
		)
		(property "Datasheet" ""
			(at 248.92 161.29 0)
			(effects
				(font
					(size 1.27 1.27)
					(thickness 0.15)
				)
				(justify left bottom)
				(hide yes)
			)
		)
		(property "Description" ""
			(at 233.68 148.59 0)
			(effects
				(font
					(size 1.27 1.27)
				)
				(hide yes)
			)
		)
		(property "MPN" ""
			(at 233.68 148.59 0)
			(effects
				(font
					(size 1.27 1.27)
				)
				(justify left bottom)
				(hide yes)
			)
		)
		(property "Manufacturer" ""
			(at 233.68 148.59 0)
			(effects
				(font
					(size 1.27 1.27)
				)
				(justify left bottom)
				(hide yes)
			)
		)
		(property "Author" "Antmicro"
			(at 248.92 163.83 0)
			(effects
				(font
					(size 1.27 1.27)
					(thickness 0.15)
				)
				(justify left bottom)
				(hide yes)
			)
		)
		(property "License" "Apache-2.0"
			(at 248.92 166.37 0)
			(effects
				(font
					(size 1.27 1.27)
					(thickness 0.15)
				)
				(justify left bottom)
				(hide yes)
			)
		)
		(property "Public" "False"
			(at 243.84 162.56 0)
			(effects
				(font
					(size 1.27 1.27)
				)
				(justify left bottom)
				(hide yes)
			)
		)
		(pin "1"
		)
		(instances
			(project "com-express-7-baseboard"
				(path ""
					(reference "TP10")
					(unit 1)
				)
			)
		)
	)
	(symbol
		(lib_id "antmicropower:GND")
		(at 130.81 207.01 0)
		(mirror y)
		(unit 1)
		(exclude_from_sim no)
		(in_bom yes)
		(on_board yes)
		(dnp no)
		(property "Reference" "#PWR057"
			(at 121.92 209.55 0)
			(effects
				(font
					(size 1.27 1.27)
					(thickness 0.15)
				)
				(justify left bottom)
				(hide yes)
			)
		)
		(property "Value" "GND"
			(at 130.81 210.82 0)
			(effects
				(font
					(size 1.27 1.27)
					(thickness 0.15)
				)
			)
		)
		(property "Footprint" ""
			(at 121.92 214.63 0)
			(effects
				(font
					(size 1.27 1.27)
					(thickness 0.15)
				)
				(justify left bottom)
				(hide yes)
			)
		)
		(property "Datasheet" ""
			(at 121.92 219.71 0)
			(effects
				(font
					(size 1.27 1.27)
					(thickness 0.15)
				)
				(justify left bottom)
				(hide yes)
			)
		)
		(property "Description" ""
			(at 130.81 207.01 0)
			(effects
				(font
					(size 1.27 1.27)
				)
				(hide yes)
			)
		)
		(property "Author" "Antmicro"
			(at 121.92 214.63 0)
			(effects
				(font
					(size 1.27 1.27)
					(thickness 0.15)
				)
				(justify left bottom)
				(hide yes)
			)
		)
		(property "License" "Apache-2.0"
			(at 121.92 217.17 0)
			(effects
				(font
					(size 1.27 1.27)
					(thickness 0.15)
				)
				(justify left bottom)
				(hide yes)
			)
		)
		(pin "1"
		)
		(instances
			(project "com-express-7-baseboard"
				(path ""
					(reference "#PWR057")
					(unit 1)
				)
			)
		)
	)
	(symbol
		(lib_id "antmicropower:GND")
		(at 147.32 120.65 0)
		(mirror y)
		(unit 1)
		(exclude_from_sim no)
		(in_bom yes)
		(on_board yes)
		(dnp no)
		(property "Reference" "#PWR060"
			(at 138.43 123.19 0)
			(effects
				(font
					(size 1.27 1.27)
					(thickness 0.15)
				)
				(justify left bottom)
				(hide yes)
			)
		)
		(property "Value" "GND"
			(at 147.32 124.46 0)
			(effects
				(font
					(size 1.27 1.27)
					(thickness 0.15)
				)
			)
		)
		(property "Footprint" ""
			(at 138.43 128.27 0)
			(effects
				(font
					(size 1.27 1.27)
					(thickness 0.15)
				)
				(justify left bottom)
				(hide yes)
			)
		)
		(property "Datasheet" ""
			(at 138.43 133.35 0)
			(effects
				(font
					(size 1.27 1.27)
					(thickness 0.15)
				)
				(justify left bottom)
				(hide yes)
			)
		)
		(property "Description" ""
			(at 147.32 120.65 0)
			(effects
				(font
					(size 1.27 1.27)
				)
				(hide yes)
			)
		)
		(property "Author" "Antmicro"
			(at 138.43 128.27 0)
			(effects
				(font
					(size 1.27 1.27)
					(thickness 0.15)
				)
				(justify left bottom)
				(hide yes)
			)
		)
		(property "License" "Apache-2.0"
			(at 138.43 130.81 0)
			(effects
				(font
					(size 1.27 1.27)
					(thickness 0.15)
				)
				(justify left bottom)
				(hide yes)
			)
		)
		(pin "1"
		)
		(instances
			(project "com-express-7-baseboard"
				(path ""
					(reference "#PWR060")
					(unit 1)
				)
			)
		)
	)
	(symbol
		(lib_id "antmicropower:GND")
		(at 293.37 119.38 0)
		(mirror y)
		(unit 1)
		(exclude_from_sim no)
		(in_bom yes)
		(on_board yes)
		(dnp no)
		(property "Reference" "#PWR069"
			(at 293.37 125.73 0)
			(effects
				(font
					(size 1.27 1.27)
				)
				(justify left bottom)
				(hide yes)
			)
		)
		(property "Value" "GND"
			(at 293.37 123.19 0)
			(effects
				(font
					(size 1.27 1.27)
				)
			)
		)
		(property "Footprint" ""
			(at 293.37 119.38 0)
			(effects
				(font
					(size 1.27 1.27)
				)
				(justify left bottom)
				(hide yes)
			)
		)
		(property "Datasheet" ""
			(at 293.37 119.38 0)
			(effects
				(font
					(size 1.27 1.27)
				)
				(justify left bottom)
				(hide yes)
			)
		)
		(property "Description" ""
			(at 293.37 119.38 0)
			(effects
				(font
					(size 1.27 1.27)
				)
				(hide yes)
			)
		)
		(property "Author" "Antmicro"
			(at 284.48 127 0)
			(effects
				(font
					(size 1.27 1.27)
					(thickness 0.15)
				)
				(justify left bottom)
				(hide yes)
			)
		)
		(property "License" "Apache-2.0"
			(at 284.48 129.54 0)
			(effects
				(font
					(size 1.27 1.27)
					(thickness 0.15)
				)
				(justify left bottom)
				(hide yes)
			)
		)
		(pin "1"
		)
		(instances
			(project "com-express-7-baseboard"
				(path ""
					(reference "#PWR069")
					(unit 1)
				)
			)
		)
	)
	(symbol
		(lib_id "antmicropower:GND")
		(at 189.23 151.13 0)
		(mirror y)
		(unit 1)
		(exclude_from_sim no)
		(in_bom yes)
		(on_board yes)
		(dnp no)
		(property "Reference" "#PWR065"
			(at 189.23 157.48 0)
			(effects
				(font
					(size 1.27 1.27)
				)
				(justify left bottom)
				(hide yes)
			)
		)
		(property "Value" "GND"
			(at 191.135 156.21 0)
			(effects
				(font
					(size 1.27 1.27)
				)
				(justify left bottom)
			)
		)
		(property "Footprint" ""
			(at 189.23 151.13 0)
			(effects
				(font
					(size 1.27 1.27)
				)
				(justify left bottom)
				(hide yes)
			)
		)
		(property "Datasheet" ""
			(at 189.23 151.13 0)
			(effects
				(font
					(size 1.27 1.27)
				)
				(justify left bottom)
				(hide yes)
			)
		)
		(property "Description" ""
			(at 189.23 151.13 0)
			(effects
				(font
					(size 1.27 1.27)
				)
				(hide yes)
			)
		)
		(property "Author" "Antmicro"
			(at 180.34 158.75 0)
			(effects
				(font
					(size 1.27 1.27)
					(thickness 0.15)
				)
				(justify left bottom)
				(hide yes)
			)
		)
		(property "License" "Apache-2.0"
			(at 180.34 161.29 0)
			(effects
				(font
					(size 1.27 1.27)
					(thickness 0.15)
				)
				(justify left bottom)
				(hide yes)
			)
		)
		(pin "1"
		)
		(instances
			(project "com-express-7-baseboard"
				(path ""
					(reference "#PWR065")
					(unit 1)
				)
			)
		)
	)
	(symbol
		(lib_id "antmicroLogicTranslatorsLevelShifters:NTS0102_TSSOP")
		(at 288.29 125.73 0)
		(mirror y)
		(unit 1)
		(exclude_from_sim no)
		(in_bom yes)
		(on_board yes)
		(dnp no)
		(fields_autoplaced yes)
		(property "Reference" "U7"
			(at 278.13 118.11 0)
			(effects
				(font
					(size 1.27 1.27)
					(thickness 0.15)
				)
			)
		)
		(property "Value" "NTS0102_TSSOP"
			(at 278.13 120.65 0)
			(effects
				(font
					(size 1.27 1.27)
					(thickness 0.15)
				)
				(hide yes)
			)
		)
		(property "Footprint" "antmicro-footprints:TSSOP-8_3x3mm_P0.65mm"
			(at 252.73 134.62 0)
			(effects
				(font
					(size 1.27 1.27)
					(thickness 0.15)
				)
				(justify left bottom)
				(hide yes)
			)
		)
		(property "Datasheet" "https://www.mouser.com/datasheet/2/302/NTS0102-1127324.pdf"
			(at 252.73 137.16 0)
			(effects
				(font
					(size 1.27 1.27)
					(thickness 0.15)
				)
				(justify left bottom)
				(hide yes)
			)
		)
		(property "Description" ""
			(at 288.29 125.73 0)
			(effects
				(font
					(size 1.27 1.27)
				)
				(hide yes)
			)
		)
		(property "MPN" "NTS0102DP"
			(at 278.13 120.65 0)
			(effects
				(font
					(size 1.27 1.27)
					(thickness 0.15)
				)
			)
		)
		(property "Manufacturer" "NXP"
			(at 252.73 142.24 0)
			(effects
				(font
					(size 1.27 1.27)
					(thickness 0.15)
				)
				(justify left bottom)
				(hide yes)
			)
		)
		(property "Author" "Antmicro"
			(at 252.73 144.78 0)
			(effects
				(font
					(size 1.27 1.27)
					(thickness 0.15)
				)
				(justify left bottom)
				(hide yes)
			)
		)
		(property "License" "Apache-2.0"
			(at 252.73 147.32 0)
			(effects
				(font
					(size 1.27 1.27)
					(thickness 0.15)
				)
				(justify left bottom)
				(hide yes)
			)
		)
		(pin "8"
		)
		(pin "3"
		)
		(pin "2"
		)
		(pin "6"
		)
		(pin "7"
		)
		(pin "5"
		)
		(pin "1"
		)
		(pin "4"
		)
		(instances
			(project "com-express-7-baseboard"
				(path ""
					(reference "U7")
					(unit 1)
				)
			)
		)
	)
	(symbol
		(lib_id "antmicroLEDIndicationDiscrete:LED_G_0603_LTST-C190GKT")
		(at 224.79 176.53 90)
		(unit 1)
		(exclude_from_sim no)
		(in_bom yes)
		(on_board yes)
		(dnp no)
		(property "Reference" "D11"
			(at 222.25 172.72 90)
			(effects
				(font
					(size 1.27 1.27)
				)
				(justify left)
			)
		)
		(property "Value" "LED_G_0603_LTST-C190GKT"
			(at 232.41 153.67 0)
			(effects
				(font
					(size 1.27 1.27)
					(thickness 0.15)
				)
				(justify left bottom)
				(hide yes)
			)
		)
		(property "Footprint" "antmicro-footprints:LED_0603_1608Metric_G"
			(at 234.95 153.67 0)
			(effects
				(font
					(size 1.27 1.27)
					(thickness 0.15)
				)
				(justify left bottom)
				(hide yes)
			)
		)
		(property "Datasheet" "https://media.digikey.com/pdf/Data%20Sheets/Lite-On%20PDFs/LTST-C190GKT.pdf"
			(at 237.49 153.67 0)
			(effects
				(font
					(size 1.27 1.27)
					(thickness 0.15)
				)
				(justify left bottom)
				(hide yes)
			)
		)
		(property "Description" ""
			(at 224.79 176.53 0)
			(effects
				(font
					(size 1.27 1.27)
				)
				(hide yes)
			)
		)
		(property "MPN" "LTST-C190GKT"
			(at 220.98 171.4501 90)
			(effects
				(font
					(size 1.27 1.27)
					(thickness 0.15)
				)
				(justify left)
				(hide yes)
			)
		)
		(property "Manufacturer" "Lite-On"
			(at 242.57 153.67 0)
			(effects
				(font
					(size 1.27 1.27)
					(thickness 0.15)
				)
				(justify left bottom)
				(hide yes)
			)
		)
		(property "Author" "Antmicro"
			(at 245.11 153.67 0)
			(effects
				(font
					(size 1.27 1.27)
					(thickness 0.15)
				)
				(justify left bottom)
				(hide yes)
			)
		)
		(property "License" "Apache-2.0"
			(at 247.65 153.67 0)
			(effects
				(font
					(size 1.27 1.27)
					(thickness 0.15)
				)
				(justify left bottom)
				(hide yes)
			)
		)
		(property "Public" "False"
			(at 242.57 156.21 0)
			(effects
				(font
					(size 1.27 1.27)
				)
				(justify left bottom)
				(hide yes)
			)
		)
		(property "Color" "Green"
			(at 222.25 175.26 90)
			(effects
				(font
					(size 1.27 1.27)
				)
				(justify left)
			)
		)
		(pin "1"
		)
		(pin "2"
		)
		(instances
			(project "com-express-7-baseboard"
				(path ""
					(reference "D11")
					(unit 1)
				)
			)
		)
	)
	(symbol
		(lib_id "antmicroResistors0402:R_0R_0402")
		(at 295.91 130.81 0)
		(unit 1)
		(exclude_from_sim no)
		(in_bom yes)
		(on_board yes)
		(dnp no)
		(property "Reference" "R75"
			(at 292.1 129.54 0)
			(effects
				(font
					(size 1.27 1.27)
					(thickness 0.15)
				)
			)
		)
		(property "Value" "R_0R_0402"
			(at 316.23 143.51 0)
			(effects
				(font
					(size 1.27 1.27)
					(thickness 0.15)
				)
				(justify left bottom)
				(hide yes)
			)
		)
		(property "Footprint" "antmicro-footprints:R_0402_1005Metric"
			(at 316.23 146.05 0)
			(effects
				(font
					(size 1.27 1.27)
					(thickness 0.15)
				)
				(justify left bottom)
				(hide yes)
			)
		)
		(property "Datasheet" "https://industrial.panasonic.com/cdbs/www-data/pdf/RDA0000/AOA0000C301.pdf"
			(at 316.23 148.59 0)
			(effects
				(font
					(size 1.27 1.27)
					(thickness 0.15)
				)
				(justify left bottom)
				(hide yes)
			)
		)
		(property "Description" ""
			(at 295.91 130.81 0)
			(effects
				(font
					(size 1.27 1.27)
				)
				(hide yes)
			)
		)
		(property "MPN" "ERJ2GE0R00X"
			(at 316.23 151.13 0)
			(effects
				(font
					(size 1.27 1.27)
					(thickness 0.15)
				)
				(justify left bottom)
				(hide yes)
			)
		)
		(property "Manufacturer" "Panasonic"
			(at 316.23 153.67 0)
			(effects
				(font
					(size 1.27 1.27)
					(thickness 0.15)
				)
				(justify left bottom)
				(hide yes)
			)
		)
		(property "License" "Apache-2.0"
			(at 316.23 156.21 0)
			(effects
				(font
					(size 1.27 1.27)
					(thickness 0.15)
				)
				(justify left bottom)
				(hide yes)
			)
		)
		(property "Author" "Antmicro"
			(at 316.23 158.75 0)
			(effects
				(font
					(size 1.27 1.27)
					(thickness 0.15)
				)
				(justify left bottom)
				(hide yes)
			)
		)
		(property "Val" "0R"
			(at 302.26 129.54 0)
			(effects
				(font
					(size 1.27 1.27)
					(thickness 0.15)
				)
			)
		)
		(property "Tolerance" "~"
			(at 316.23 140.97 0)
			(effects
				(font
					(size 1.27 1.27)
				)
				(justify left bottom)
				(hide yes)
			)
		)
		(property "Current" "1A"
			(at 316.23 161.29 0)
			(effects
				(font
					(size 1.27 1.27)
					(thickness 0.15)
				)
				(justify left bottom)
				(hide yes)
			)
		)
		(property "Public" "False"
			(at 316.23 161.29 0)
			(effects
				(font
					(size 1.27 1.27)
				)
				(justify left bottom)
				(hide yes)
			)
		)
		(pin "1"
		)
		(pin "2"
		)
		(instances
			(project "com-express-7-baseboard"
				(path ""
					(reference "R75")
					(unit 1)
				)
			)
		)
	)
)
